FILE_TYPE = MACRO_DRAWING;
SET COLOR_WIRE YELLOW;
SET COLOR_PROP ORANGE;
SET COLOR_DOT WHITE;
SET COLOR_ARC YELLOW;
SET COLOR_BODY GREEN;
SET COLOR_NOTE PURPLE;
SET PROP_DISPLAY VALUE;
SET PAGE_NUMBER P198;
FORCEADD OFFPAGE..1
(-7500 -3825);
FORCEPROP 2 LAST $XR0 208 
J 0
(-7752 -3825);
DISPLAY 0.638298 (-7752 -3825);
PAINT MONO (-7752 -3825);
FORCEPROP 1 LAST COMMENT_BODY TRUE
J 0
(-7375 -3925);
DISPLAY 0.872340 (-7375 -3925);
PAINT GREEN (-7375 -3925);
DISPLAY INVISIBLE (-7375 -3925);
FORCEPROP 1 LAST OFFPAGE TRUE
J 0
(-7175 -3950);
DISPLAY 0.872340 (-7175 -3950);
DISPLAY INVISIBLE (-7175 -3950);
FORCEPROP 2 LAST CDS_LIB standard
J 0
(-7500 -3825);
PAINT MONO (-7500 -3825);
DISPLAY INVISIBLE (-7500 -3825);
FORCEPROP 2 LAST PATH I1
J 0
(-7750 -3775);
DISPLAY 1.021277 (-7750 -3775);
DISPLAY INVISIBLE (-7750 -3775);
FORCEADD Q_RES..1
(-6100 -2725);
FORCEPROP 1 LAST PART_NUMBER CS00002JB13
J 0
(-6175 -2700);
DISPLAY 0.319149 (-6175 -2700);
DISPLAY INVISIBLE (-6175 -2700);
FORCEPROP 1 LAST PACK_TYPE 0402LF
J 0
(-6175 -2675);
DISPLAY 0.319149 (-6175 -2675);
FORCEPROP 1 LAST VALUE 0
J 2
(-5950 -2725);
DISPLAY 0.404255 (-5950 -2725);
FORCEPROP 1 LAST TOLERANCE 5%
J 0
(-5925 -2725);
DISPLAY 0.404255 (-5925 -2725);
FORCEPROP 1 LAST MATERIAL CHIP
J 0
(-5875 -2725);
DISPLAY 0.404255 (-5875 -2725);
FORCEPROP 1 LAST WATTAGE 1/16W
J 2
(-5975 -2675);
DISPLAY 0.319149 (-5975 -2675);
FORCEPROP 1 LAST $LOCATION R1018
J 0
(-6300 -2725);
DISPLAY 0.510638 (-6300 -2725);
FORCEPROP 1 LASTPIN (-6200 -2725) $PN 1
J 0
(-6188 -2713);
DISPLAY 0.787234 (-6188 -2713);
FORCEPROP 1 LASTPIN (-6000 -2725) $PN 2
J 0
(-6038 -2713);
DISPLAY 0.787234 (-6038 -2713);
FORCEPROP 2 LAST CDS_LIB pure_quanta
J 0
(-6100 -2725);
PAINT MONO (-6100 -2725);
DISPLAY INVISIBLE (-6100 -2725);
FORCEPROP 1 LAST PATH I10
J 0
(-6150 -2575);
DISPLAY 0.978723 (-6150 -2575);
PAINT WHITE (-6150 -2575);
DISPLAY INVISIBLE (-6150 -2575);
FORCEPROP 2 LAST CDS_LOCATION R1018
J 0
(-6150 -2525);
DISPLAY 1.021277 (-6150 -2525);
DISPLAY INVISIBLE (-6150 -2525);
FORCEPROP 2 LAST $SEC 1
J 0
(-6150 -2525);
DISPLAY 0.680851 (-6150 -2525);
PAINT MONO (-6150 -2525);
DISPLAY INVISIBLE (-6150 -2525);
FORCEPROP 2 LAST CDS_SEC 1
J 0
(-6150 -2525);
DISPLAY 1.021277 (-6150 -2525);
DISPLAY INVISIBLE (-6150 -2525);
FORCEADD Q_RES..1
(-6100 -2550);
FORCEPROP 1 LAST PART_NUMBER CS00002JB13
J 0
(-6175 -2525);
DISPLAY 0.319149 (-6175 -2525);
DISPLAY INVISIBLE (-6175 -2525);
FORCEPROP 1 LAST MATERIAL EMPTY
J 0
(-5875 -2550);
DISPLAY 0.404255 (-5875 -2550);
PAINT RED (-5875 -2550);
FORCEPROP 1 LAST VALUE 0
J 2
(-5950 -2550);
DISPLAY 0.404255 (-5950 -2550);
FORCEPROP 1 LAST TOLERANCE 5%
J 0
(-5925 -2550);
DISPLAY 0.404255 (-5925 -2550);
FORCEPROP 1 LAST PACK_TYPE 0402LF
J 0
(-6175 -2500);
DISPLAY 0.319149 (-6175 -2500);
FORCEPROP 1 LAST WATTAGE 1/16W
J 2
(-5975 -2500);
DISPLAY 0.319149 (-5975 -2500);
FORCEPROP 1 LAST $LOCATION R1017
J 0
(-6300 -2550);
DISPLAY 0.510638 (-6300 -2550);
FORCEPROP 1 LASTPIN (-6200 -2550) $PN 1
J 0
(-6188 -2538);
DISPLAY 0.787234 (-6188 -2538);
FORCEPROP 1 LASTPIN (-6000 -2550) $PN 2
J 0
(-6038 -2538);
DISPLAY 0.787234 (-6038 -2538);
FORCEPROP 2 LAST CDS_LIB pure_quanta
J 0
(-6100 -2550);
PAINT MONO (-6100 -2550);
DISPLAY INVISIBLE (-6100 -2550);
FORCEPROP 1 LAST PATH I11
J 0
(-6150 -2400);
DISPLAY 0.978723 (-6150 -2400);
PAINT WHITE (-6150 -2400);
DISPLAY INVISIBLE (-6150 -2400);
FORCEPROP 2 LAST CDS_LOCATION R1017
J 0
(-6150 -2350);
DISPLAY 1.021277 (-6150 -2350);
DISPLAY INVISIBLE (-6150 -2350);
FORCEPROP 2 LAST $SEC 1
J 0
(-6150 -2350);
DISPLAY 0.680851 (-6150 -2350);
PAINT MONO (-6150 -2350);
DISPLAY INVISIBLE (-6150 -2350);
FORCEPROP 2 LAST CDS_SEC 1
J 0
(-6150 -2350);
DISPLAY 1.021277 (-6150 -2350);
DISPLAY INVISIBLE (-6150 -2350);
FORCEADD Q_RES..1
(-6100 -2375);
FORCEPROP 1 LAST PART_NUMBER CS00002JB13
J 0
(-6175 -2350);
DISPLAY 0.319149 (-6175 -2350);
DISPLAY INVISIBLE (-6175 -2350);
FORCEPROP 1 LAST WATTAGE 1/16W
J 2
(-5975 -2325);
DISPLAY 0.319149 (-5975 -2325);
FORCEPROP 1 LAST PACK_TYPE 0402LF
J 0
(-6175 -2325);
DISPLAY 0.319149 (-6175 -2325);
FORCEPROP 1 LAST MATERIAL CHIP
J 0
(-5875 -2375);
DISPLAY 0.404255 (-5875 -2375);
FORCEPROP 1 LAST TOLERANCE 5%
J 0
(-5925 -2375);
DISPLAY 0.404255 (-5925 -2375);
FORCEPROP 1 LAST VALUE 0
J 2
(-5950 -2375);
DISPLAY 0.404255 (-5950 -2375);
FORCEPROP 1 LAST $LOCATION R1016
J 0
(-6300 -2375);
DISPLAY 0.510638 (-6300 -2375);
FORCEPROP 1 LASTPIN (-6200 -2375) $PN 1
J 0
(-6188 -2363);
DISPLAY 0.787234 (-6188 -2363);
FORCEPROP 1 LASTPIN (-6000 -2375) $PN 2
J 0
(-6038 -2363);
DISPLAY 0.787234 (-6038 -2363);
FORCEPROP 2 LAST CDS_LIB pure_quanta
J 0
(-6100 -2375);
PAINT MONO (-6100 -2375);
DISPLAY INVISIBLE (-6100 -2375);
FORCEPROP 1 LAST PATH I12
J 0
(-6150 -2225);
DISPLAY 0.978723 (-6150 -2225);
PAINT WHITE (-6150 -2225);
DISPLAY INVISIBLE (-6150 -2225);
FORCEPROP 2 LAST CDS_LOCATION R1016
J 0
(-6150 -2175);
DISPLAY 1.021277 (-6150 -2175);
DISPLAY INVISIBLE (-6150 -2175);
FORCEPROP 2 LAST $SEC 1
J 0
(-6150 -2175);
DISPLAY 0.680851 (-6150 -2175);
PAINT MONO (-6150 -2175);
DISPLAY INVISIBLE (-6150 -2175);
FORCEPROP 2 LAST CDS_SEC 1
J 0
(-6150 -2175);
DISPLAY 1.021277 (-6150 -2175);
DISPLAY INVISIBLE (-6150 -2175);
FORCEADD OFFPAGE..1
(-7475 -1600);
FORCEPROP 2 LAST $XR0 179 
J 0
(-7727 -1600);
DISPLAY 0.638298 (-7727 -1600);
PAINT MONO (-7727 -1600);
FORCEPROP 2 LAST CDS_LIB standard
J 0
(-7475 -1600);
PAINT MONO (-7475 -1600);
DISPLAY INVISIBLE (-7475 -1600);
FORCEPROP 1 LAST OFFPAGE TRUE
J 0
(-7150 -1725);
DISPLAY 0.872340 (-7150 -1725);
DISPLAY INVISIBLE (-7150 -1725);
FORCEPROP 1 LAST COMMENT_BODY TRUE
J 0
(-7350 -1700);
DISPLAY 0.872340 (-7350 -1700);
PAINT GREEN (-7350 -1700);
DISPLAY INVISIBLE (-7350 -1700);
FORCEPROP 2 LAST PATH I13
J 0
(-7725 -1550);
DISPLAY 1.021277 (-7725 -1550);
DISPLAY INVISIBLE (-7725 -1550);
FORCEADD OFFPAGE..1
(-7475 -1425);
FORCEPROP 2 LAST $XR0 208 
J 0
(-7727 -1425);
DISPLAY 0.638298 (-7727 -1425);
PAINT MONO (-7727 -1425);
FORCEPROP 2 LAST CDS_LIB standard
J 0
(-7475 -1425);
PAINT MONO (-7475 -1425);
DISPLAY INVISIBLE (-7475 -1425);
FORCEPROP 1 LAST OFFPAGE TRUE
J 0
(-7150 -1550);
DISPLAY 0.872340 (-7150 -1550);
DISPLAY INVISIBLE (-7150 -1550);
FORCEPROP 1 LAST COMMENT_BODY TRUE
J 0
(-7350 -1525);
DISPLAY 0.872340 (-7350 -1525);
PAINT GREEN (-7350 -1525);
DISPLAY INVISIBLE (-7350 -1525);
FORCEPROP 2 LAST PATH I14
J 0
(-7725 -1375);
DISPLAY 1.021277 (-7725 -1375);
DISPLAY INVISIBLE (-7725 -1375);
FORCEADD OFFPAGE..1
(-7475 -1250);
FORCEPROP 2 LAST $XR0 179 
J 0
(-7727 -1250);
DISPLAY 0.638298 (-7727 -1250);
PAINT MONO (-7727 -1250);
FORCEPROP 1 LAST COMMENT_BODY TRUE
J 0
(-7350 -1350);
DISPLAY 0.872340 (-7350 -1350);
PAINT GREEN (-7350 -1350);
DISPLAY INVISIBLE (-7350 -1350);
FORCEPROP 1 LAST OFFPAGE TRUE
J 0
(-7150 -1375);
DISPLAY 0.872340 (-7150 -1375);
DISPLAY INVISIBLE (-7150 -1375);
FORCEPROP 2 LAST CDS_LIB standard
J 0
(-7475 -1250);
PAINT MONO (-7475 -1250);
DISPLAY INVISIBLE (-7475 -1250);
FORCEPROP 2 LAST PATH I15
J 0
(-7725 -1200);
DISPLAY 1.021277 (-7725 -1200);
DISPLAY INVISIBLE (-7725 -1200);
FORCEADD OFFPAGE..1
(-7475 -1075);
FORCEPROP 2 LAST $XR0 208 
J 0
(-7727 -1075);
DISPLAY 0.638298 (-7727 -1075);
PAINT MONO (-7727 -1075);
FORCEPROP 1 LAST COMMENT_BODY TRUE
J 0
(-7350 -1175);
DISPLAY 0.872340 (-7350 -1175);
PAINT GREEN (-7350 -1175);
DISPLAY INVISIBLE (-7350 -1175);
FORCEPROP 1 LAST OFFPAGE TRUE
J 0
(-7150 -1200);
DISPLAY 0.872340 (-7150 -1200);
DISPLAY INVISIBLE (-7150 -1200);
FORCEPROP 2 LAST CDS_LIB standard
J 0
(-7475 -1075);
PAINT MONO (-7475 -1075);
DISPLAY INVISIBLE (-7475 -1075);
FORCEPROP 2 LAST PATH I16
J 0
(-7725 -1025);
DISPLAY 1.021277 (-7725 -1025);
DISPLAY INVISIBLE (-7725 -1025);
FORCEADD OFFPAGE..1
(-7450 -200);
FORCEPROP 2 LAST $XR0 206 
J 0
(-7732 -200);
DISPLAY 0.638298 (-7732 -200);
PAINT MONO (-7732 -200);
FORCEPROP 2 LAST CDS_LIB standard
J 0
(-7450 -200);
DISPLAY INVISIBLE (-7450 -200);
FORCEPROP 1 LAST OFFPAGE TRUE
J 0
(-7125 -325);
DISPLAY 0.872340 (-7125 -325);
DISPLAY INVISIBLE (-7125 -325);
FORCEPROP 1 LAST COMMENT_BODY TRUE
J 0
(-7325 -300);
DISPLAY 0.872340 (-7325 -300);
PAINT GREEN (-7325 -300);
DISPLAY INVISIBLE (-7325 -300);
FORCEPROP 2 LAST PATH I17
J 0
(-7725 -150);
DISPLAY 1.021277 (-7725 -150);
DISPLAY INVISIBLE (-7725 -150);
FORCEADD OFFPAGE..1
(-7450 -350);
FORCEPROP 2 LAST $XR0 206 
J 0
(-7732 -350);
DISPLAY 0.638298 (-7732 -350);
PAINT MONO (-7732 -350);
FORCEPROP 2 LAST CDS_LIB standard
J 0
(-7450 -350);
DISPLAY INVISIBLE (-7450 -350);
FORCEPROP 1 LAST OFFPAGE TRUE
J 0
(-7125 -475);
DISPLAY 0.872340 (-7125 -475);
DISPLAY INVISIBLE (-7125 -475);
FORCEPROP 1 LAST COMMENT_BODY TRUE
J 0
(-7325 -450);
DISPLAY 0.872340 (-7325 -450);
PAINT GREEN (-7325 -450);
DISPLAY INVISIBLE (-7325 -450);
FORCEPROP 2 LAST PATH I18
J 0
(-7725 -300);
DISPLAY 1.021277 (-7725 -300);
DISPLAY INVISIBLE (-7725 -300);
FORCEADD Q_RES..1
(-6100 -1600);
FORCEPROP 1 LAST PART_NUMBER CS00002JB13
J 0
(-6175 -1575);
DISPLAY 0.319149 (-6175 -1575);
DISPLAY INVISIBLE (-6175 -1575);
FORCEPROP 1 LAST PACK_TYPE 0402LF
J 0
(-6175 -1550);
DISPLAY 0.319149 (-6175 -1550);
FORCEPROP 1 LAST WATTAGE 1/16W
J 2
(-5975 -1550);
DISPLAY 0.319149 (-5975 -1550);
FORCEPROP 1 LAST VALUE 0
J 2
(-5950 -1600);
DISPLAY 0.404255 (-5950 -1600);
FORCEPROP 1 LAST TOLERANCE 5%
J 0
(-5925 -1600);
DISPLAY 0.404255 (-5925 -1600);
FORCEPROP 1 LAST MATERIAL EMPTY
J 0
(-5875 -1600);
DISPLAY 0.404255 (-5875 -1600);
PAINT RED (-5875 -1600);
FORCEPROP 1 LAST $LOCATION R1015
J 0
(-6300 -1600);
DISPLAY 0.510638 (-6300 -1600);
FORCEPROP 1 LASTPIN (-6200 -1600) $PN 1
J 0
(-6188 -1588);
DISPLAY 0.787234 (-6188 -1588);
FORCEPROP 1 LASTPIN (-6000 -1600) $PN 2
J 0
(-6038 -1588);
DISPLAY 0.787234 (-6038 -1588);
FORCEPROP 2 LAST CDS_LIB pure_quanta
J 0
(-6100 -1600);
PAINT MONO (-6100 -1600);
DISPLAY INVISIBLE (-6100 -1600);
FORCEPROP 1 LAST PATH I19
J 0
(-6150 -1450);
DISPLAY 0.978723 (-6150 -1450);
PAINT WHITE (-6150 -1450);
DISPLAY INVISIBLE (-6150 -1450);
FORCEPROP 2 LAST CDS_LOCATION R1015
J 0
(-6150 -1400);
DISPLAY 1.021277 (-6150 -1400);
DISPLAY INVISIBLE (-6150 -1400);
FORCEPROP 2 LAST $SEC 1
J 0
(-6150 -1400);
DISPLAY 0.680851 (-6150 -1400);
PAINT MONO (-6150 -1400);
DISPLAY INVISIBLE (-6150 -1400);
FORCEPROP 2 LAST CDS_SEC 1
J 0
(-6150 -1400);
DISPLAY 1.021277 (-6150 -1400);
DISPLAY INVISIBLE (-6150 -1400);
FORCEADD OFFPAGE..1
(-7500 -3650);
FORCEPROP 2 LAST $XR0 208 
J 0
(-7752 -3650);
DISPLAY 0.638298 (-7752 -3650);
PAINT MONO (-7752 -3650);
FORCEPROP 2 LAST CDS_LIB standard
J 0
(-7500 -3650);
PAINT MONO (-7500 -3650);
DISPLAY INVISIBLE (-7500 -3650);
FORCEPROP 1 LAST OFFPAGE TRUE
J 0
(-7175 -3775);
DISPLAY 0.872340 (-7175 -3775);
DISPLAY INVISIBLE (-7175 -3775);
FORCEPROP 1 LAST COMMENT_BODY TRUE
J 0
(-7375 -3750);
DISPLAY 0.872340 (-7375 -3750);
PAINT GREEN (-7375 -3750);
DISPLAY INVISIBLE (-7375 -3750);
FORCEPROP 2 LAST PATH I2
J 0
(-7750 -3600);
DISPLAY 1.021277 (-7750 -3600);
DISPLAY INVISIBLE (-7750 -3600);
FORCEADD Q_RES..1
(-6100 -1425);
FORCEPROP 1 LAST PART_NUMBER CS00002JB13
J 0
(-6175 -1400);
DISPLAY 0.319149 (-6175 -1400);
DISPLAY INVISIBLE (-6175 -1400);
FORCEPROP 1 LAST VALUE 0
J 2
(-5950 -1425);
DISPLAY 0.404255 (-5950 -1425);
FORCEPROP 1 LAST TOLERANCE 5%
J 0
(-5925 -1425);
DISPLAY 0.404255 (-5925 -1425);
FORCEPROP 1 LAST MATERIAL CHIP
J 0
(-5875 -1425);
DISPLAY 0.404255 (-5875 -1425);
FORCEPROP 1 LAST WATTAGE 1/16W
J 2
(-5975 -1375);
DISPLAY 0.319149 (-5975 -1375);
FORCEPROP 1 LAST PACK_TYPE 0402LF
J 0
(-6175 -1375);
DISPLAY 0.319149 (-6175 -1375);
FORCEPROP 1 LAST $LOCATION R1014
J 0
(-6300 -1425);
DISPLAY 0.510638 (-6300 -1425);
FORCEPROP 1 LASTPIN (-6200 -1425) $PN 1
J 0
(-6188 -1413);
DISPLAY 0.787234 (-6188 -1413);
FORCEPROP 1 LASTPIN (-6000 -1425) $PN 2
J 0
(-6038 -1413);
DISPLAY 0.787234 (-6038 -1413);
FORCEPROP 2 LAST CDS_LIB pure_quanta
J 0
(-6100 -1425);
PAINT MONO (-6100 -1425);
DISPLAY INVISIBLE (-6100 -1425);
FORCEPROP 1 LAST PATH I20
J 0
(-6150 -1275);
DISPLAY 0.978723 (-6150 -1275);
PAINT WHITE (-6150 -1275);
DISPLAY INVISIBLE (-6150 -1275);
FORCEPROP 2 LAST CDS_LOCATION R1014
J 0
(-6150 -1225);
DISPLAY 1.021277 (-6150 -1225);
DISPLAY INVISIBLE (-6150 -1225);
FORCEPROP 2 LAST $SEC 1
J 0
(-6150 -1225);
DISPLAY 0.680851 (-6150 -1225);
PAINT MONO (-6150 -1225);
DISPLAY INVISIBLE (-6150 -1225);
FORCEPROP 2 LAST CDS_SEC 1
J 0
(-6150 -1225);
DISPLAY 1.021277 (-6150 -1225);
DISPLAY INVISIBLE (-6150 -1225);
FORCEADD Q_RES..1
(-6100 -1250);
FORCEPROP 1 LAST PART_NUMBER CS00002JB13
J 0
(-6175 -1225);
DISPLAY 0.319149 (-6175 -1225);
DISPLAY INVISIBLE (-6175 -1225);
FORCEPROP 1 LAST VALUE 0
J 2
(-5950 -1250);
DISPLAY 0.404255 (-5950 -1250);
FORCEPROP 1 LAST WATTAGE 1/16W
J 2
(-5975 -1200);
DISPLAY 0.319149 (-5975 -1200);
FORCEPROP 1 LAST PACK_TYPE 0402LF
J 0
(-6175 -1200);
DISPLAY 0.319149 (-6175 -1200);
FORCEPROP 1 LAST TOLERANCE 5%
J 0
(-5925 -1250);
DISPLAY 0.404255 (-5925 -1250);
FORCEPROP 1 LAST MATERIAL EMPTY
J 0
(-5875 -1250);
DISPLAY 0.404255 (-5875 -1250);
PAINT RED (-5875 -1250);
FORCEPROP 1 LAST $LOCATION R1013
J 0
(-6300 -1250);
DISPLAY 0.510638 (-6300 -1250);
FORCEPROP 1 LASTPIN (-6200 -1250) $PN 1
J 0
(-6188 -1238);
DISPLAY 0.787234 (-6188 -1238);
FORCEPROP 1 LASTPIN (-6000 -1250) $PN 2
J 0
(-6038 -1238);
DISPLAY 0.787234 (-6038 -1238);
FORCEPROP 2 LAST CDS_LIB pure_quanta
J 0
(-6100 -1250);
PAINT MONO (-6100 -1250);
DISPLAY INVISIBLE (-6100 -1250);
FORCEPROP 1 LAST PATH I21
J 0
(-6150 -1100);
DISPLAY 0.978723 (-6150 -1100);
PAINT WHITE (-6150 -1100);
DISPLAY INVISIBLE (-6150 -1100);
FORCEPROP 2 LAST CDS_LOCATION R1013
J 0
(-6150 -1050);
DISPLAY 1.021277 (-6150 -1050);
DISPLAY INVISIBLE (-6150 -1050);
FORCEPROP 2 LAST $SEC 1
J 0
(-6150 -1050);
DISPLAY 0.680851 (-6150 -1050);
PAINT MONO (-6150 -1050);
DISPLAY INVISIBLE (-6150 -1050);
FORCEPROP 2 LAST CDS_SEC 1
J 0
(-6150 -1050);
DISPLAY 1.021277 (-6150 -1050);
DISPLAY INVISIBLE (-6150 -1050);
FORCEADD Q_RES..1
(-6100 -1075);
FORCEPROP 1 LAST PART_NUMBER CS00002JB13
J 0
(-6175 -1050);
DISPLAY 0.319149 (-6175 -1050);
DISPLAY INVISIBLE (-6175 -1050);
FORCEPROP 1 LAST TOLERANCE 5%
J 0
(-5925 -1075);
DISPLAY 0.404255 (-5925 -1075);
FORCEPROP 1 LAST MATERIAL CHIP
J 0
(-5875 -1075);
DISPLAY 0.404255 (-5875 -1075);
FORCEPROP 1 LAST VALUE 0
J 2
(-5950 -1075);
DISPLAY 0.404255 (-5950 -1075);
FORCEPROP 1 LAST PACK_TYPE 0402LF
J 0
(-6175 -1025);
DISPLAY 0.319149 (-6175 -1025);
FORCEPROP 1 LAST WATTAGE 1/16W
J 2
(-5975 -1025);
DISPLAY 0.319149 (-5975 -1025);
FORCEPROP 1 LAST $LOCATION R1012
J 0
(-6300 -1075);
DISPLAY 0.510638 (-6300 -1075);
FORCEPROP 1 LASTPIN (-6200 -1075) $PN 1
J 0
(-6188 -1063);
DISPLAY 0.787234 (-6188 -1063);
FORCEPROP 1 LASTPIN (-6000 -1075) $PN 2
J 0
(-6038 -1063);
DISPLAY 0.787234 (-6038 -1063);
FORCEPROP 2 LAST CDS_LIB pure_quanta
J 0
(-6100 -1075);
PAINT MONO (-6100 -1075);
DISPLAY INVISIBLE (-6100 -1075);
FORCEPROP 1 LAST PATH I22
J 0
(-6150 -925);
DISPLAY 0.978723 (-6150 -925);
PAINT WHITE (-6150 -925);
DISPLAY INVISIBLE (-6150 -925);
FORCEPROP 2 LAST CDS_LOCATION R1012
J 0
(-6150 -875);
DISPLAY 1.021277 (-6150 -875);
DISPLAY INVISIBLE (-6150 -875);
FORCEPROP 2 LAST $SEC 1
J 0
(-6150 -875);
DISPLAY 0.680851 (-6150 -875);
PAINT MONO (-6150 -875);
DISPLAY INVISIBLE (-6150 -875);
FORCEPROP 2 LAST CDS_SEC 1
J 0
(-6150 -875);
DISPLAY 1.021277 (-6150 -875);
DISPLAY INVISIBLE (-6150 -875);
FORCEADD Q_RES..1
(-6025 -350);
FORCEPROP 1 LAST PART_NUMBER CS02202FB02
J 0
(-5900 -300);
DISPLAY 0.638298 (-5900 -300);
DISPLAY INVISIBLE (-5900 -300);
FORCEPROP 1 LAST PACK_TYPE 0402LF
J 0
(-5625 -350);
DISPLAY 0.787234 (-5625 -350);
FORCEPROP 1 LAST TOLERANCE 1%
J 0
(-5725 -350);
DISPLAY 0.787234 (-5725 -350);
FORCEPROP 1 LAST WATTAGE 1/16W
J 2
(-5550 -250);
DISPLAY 0.638298 (-5550 -250);
FORCEPROP 1 LAST VALUE 22
J 2
(-5750 -350);
DISPLAY 0.787234 (-5750 -350);
FORCEPROP 1 LAST MATERIAL CHIP
J 0
(-5900 -250);
DISPLAY 0.638298 (-5900 -250);
FORCEPROP 1 LAST $LOCATION R1276
J 0
(-6275 -350);
DISPLAY 0.808511 (-6275 -350);
FORCEPROP 1 LASTPIN (-6125 -350) $PN 1
J 0
(-6113 -338);
DISPLAY 0.787234 (-6113 -338);
FORCEPROP 1 LASTPIN (-5925 -350) $PN 2
J 0
(-5963 -338);
DISPLAY 0.787234 (-5963 -338);
FORCEPROP 2 LAST CDS_LIB pure_quanta
J 0
(-6025 -350);
PAINT MONO (-6025 -350);
DISPLAY INVISIBLE (-6025 -350);
FORCEPROP 1 LAST PATH I23
J 0
(-6075 -200);
DISPLAY 0.978723 (-6075 -200);
PAINT WHITE (-6075 -200);
DISPLAY INVISIBLE (-6075 -200);
FORCEPROP 2 LAST CDS_LOCATION R1276
J 0
(-6075 -150);
DISPLAY 1.021277 (-6075 -150);
DISPLAY INVISIBLE (-6075 -150);
FORCEPROP 2 LAST $SEC 1
J 0
(-6075 -150);
DISPLAY 0.680851 (-6075 -150);
PAINT MONO (-6075 -150);
DISPLAY INVISIBLE (-6075 -150);
FORCEPROP 2 LAST CDS_SEC 1
J 0
(-6075 -150);
DISPLAY 1.021277 (-6075 -150);
DISPLAY INVISIBLE (-6075 -150);
FORCEADD Q_RES..1
(-6025 -200);
FORCEPROP 1 LAST PART_NUMBER CS02202FB02
J 0
(-5900 -150);
DISPLAY 0.638298 (-5900 -150);
DISPLAY INVISIBLE (-5900 -150);
FORCEPROP 1 LAST MATERIAL CHIP
J 0
(-5900 -100);
DISPLAY 0.638298 (-5900 -100);
FORCEPROP 1 LAST PACK_TYPE 0402LF
J 0
(-5625 -200);
DISPLAY 0.787234 (-5625 -200);
FORCEPROP 1 LAST TOLERANCE 1%
J 0
(-5725 -200);
DISPLAY 0.787234 (-5725 -200);
FORCEPROP 1 LAST WATTAGE 1/16W
J 2
(-5550 -100);
DISPLAY 0.638298 (-5550 -100);
FORCEPROP 1 LAST VALUE 22
J 2
(-5750 -200);
DISPLAY 0.787234 (-5750 -200);
FORCEPROP 1 LAST $LOCATION R1275
J 0
(-6275 -200);
DISPLAY 0.808511 (-6275 -200);
FORCEPROP 1 LASTPIN (-6125 -200) $PN 1
J 0
(-6113 -188);
DISPLAY 0.787234 (-6113 -188);
FORCEPROP 1 LASTPIN (-5925 -200) $PN 2
J 0
(-5963 -188);
DISPLAY 0.787234 (-5963 -188);
FORCEPROP 2 LAST CDS_LIB pure_quanta
J 0
(-6025 -200);
PAINT MONO (-6025 -200);
DISPLAY INVISIBLE (-6025 -200);
FORCEPROP 1 LAST PATH I24
J 0
(-6075 -50);
DISPLAY 0.978723 (-6075 -50);
PAINT WHITE (-6075 -50);
DISPLAY INVISIBLE (-6075 -50);
FORCEPROP 2 LAST CDS_LOCATION R1275
J 0
(-6075 0);
DISPLAY 1.021277 (-6075 0);
DISPLAY INVISIBLE (-6075 0);
FORCEPROP 2 LAST $SEC 1
J 0
(-6075 0);
DISPLAY 0.680851 (-6075 0);
PAINT MONO (-6075 0);
DISPLAY INVISIBLE (-6075 0);
FORCEPROP 2 LAST CDS_SEC 1
J 0
(-6075 0);
DISPLAY 1.021277 (-6075 0);
DISPLAY INVISIBLE (-6075 0);
FORCEADD OFFPAGE..2
(-4550 -3825);
FORCEPROP 2 LAST $XR0 179 
J 0
(-4361 -3825);
DISPLAY 0.638298 (-4361 -3825);
PAINT MONO (-4361 -3825);
FORCEPROP 1 LAST OFFPAGE TRUE
J 0
(-4225 -3950);
DISPLAY 0.872340 (-4225 -3950);
DISPLAY INVISIBLE (-4225 -3950);
FORCEPROP 1 LAST COMMENT_BODY TRUE
J 0
(-4595 -3920);
DISPLAY 0.872340 (-4595 -3920);
PAINT GREEN (-4595 -3920);
DISPLAY INVISIBLE (-4595 -3920);
FORCEPROP 2 LAST CDS_LIB standard
J 0
(-4550 -3825);
PAINT MONO (-4550 -3825);
DISPLAY INVISIBLE (-4550 -3825);
FORCEPROP 2 LAST PATH I25
J 0
(-4350 -3775);
DISPLAY 1.021277 (-4350 -3775);
DISPLAY INVISIBLE (-4350 -3775);
FORCEADD OFFPAGE..2
(-4550 -3650);
FORCEPROP 2 LAST $XR0 179 
J 0
(-4361 -3650);
DISPLAY 0.638298 (-4361 -3650);
PAINT MONO (-4361 -3650);
FORCEPROP 2 LAST CDS_LIB standard
J 0
(-4550 -3650);
PAINT MONO (-4550 -3650);
DISPLAY INVISIBLE (-4550 -3650);
FORCEPROP 1 LAST COMMENT_BODY TRUE
J 0
(-4595 -3745);
DISPLAY 0.872340 (-4595 -3745);
PAINT GREEN (-4595 -3745);
DISPLAY INVISIBLE (-4595 -3745);
FORCEPROP 1 LAST OFFPAGE TRUE
J 0
(-4225 -3775);
DISPLAY 0.872340 (-4225 -3775);
DISPLAY INVISIBLE (-4225 -3775);
FORCEPROP 2 LAST PATH I26
J 0
(-4350 -3600);
DISPLAY 1.021277 (-4350 -3600);
DISPLAY INVISIBLE (-4350 -3600);
FORCEADD Q_RES..1
(-4375 -2725);
FORCEPROP 1 LAST PART_NUMBER CS00002JB13
J 0
(-4450 -2700);
DISPLAY 0.319149 (-4450 -2700);
DISPLAY INVISIBLE (-4450 -2700);
FORCEPROP 1 LAST TOLERANCE 5%
J 0
(-4200 -2725);
DISPLAY 0.404255 (-4200 -2725);
FORCEPROP 1 LAST VALUE 0
J 2
(-4225 -2725);
DISPLAY 0.404255 (-4225 -2725);
FORCEPROP 1 LAST MATERIAL CHIP
J 0
(-4150 -2725);
DISPLAY 0.404255 (-4150 -2725);
FORCEPROP 1 LAST WATTAGE 1/16W
J 2
(-4250 -2675);
DISPLAY 0.319149 (-4250 -2675);
FORCEPROP 1 LAST PACK_TYPE 0402LF
J 0
(-4450 -2675);
DISPLAY 0.319149 (-4450 -2675);
FORCEPROP 1 LAST $LOCATION R1023
J 0
(-4575 -2725);
DISPLAY 0.510638 (-4575 -2725);
FORCEPROP 1 LASTPIN (-4475 -2725) $PN 1
J 0
(-4463 -2713);
DISPLAY 0.787234 (-4463 -2713);
FORCEPROP 1 LASTPIN (-4275 -2725) $PN 2
J 0
(-4313 -2713);
DISPLAY 0.787234 (-4313 -2713);
FORCEPROP 2 LAST CDS_LIB pure_quanta
J 0
(-4375 -2725);
PAINT MONO (-4375 -2725);
DISPLAY INVISIBLE (-4375 -2725);
FORCEPROP 1 LAST PATH I27
J 0
(-4425 -2575);
DISPLAY 0.978723 (-4425 -2575);
PAINT WHITE (-4425 -2575);
DISPLAY INVISIBLE (-4425 -2575);
FORCEPROP 2 LAST CDS_LOCATION R1023
J 0
(-4425 -2525);
DISPLAY 1.021277 (-4425 -2525);
DISPLAY INVISIBLE (-4425 -2525);
FORCEPROP 2 LAST $SEC 1
J 0
(-4425 -2525);
DISPLAY 0.680851 (-4425 -2525);
PAINT MONO (-4425 -2525);
DISPLAY INVISIBLE (-4425 -2525);
FORCEPROP 2 LAST CDS_SEC 1
J 0
(-4425 -2525);
DISPLAY 1.021277 (-4425 -2525);
DISPLAY INVISIBLE (-4425 -2525);
FORCEADD Q_RES..1
(-4375 -2375);
FORCEPROP 1 LAST PART_NUMBER CS00002JB13
J 0
(-4450 -2350);
DISPLAY 0.319149 (-4450 -2350);
DISPLAY INVISIBLE (-4450 -2350);
FORCEPROP 1 LAST WATTAGE 1/16W
J 2
(-4250 -2325);
DISPLAY 0.319149 (-4250 -2325);
FORCEPROP 1 LAST VALUE 0
J 2
(-4225 -2375);
DISPLAY 0.404255 (-4225 -2375);
FORCEPROP 1 LAST TOLERANCE 5%
J 0
(-4200 -2375);
DISPLAY 0.404255 (-4200 -2375);
FORCEPROP 1 LAST MATERIAL CHIP
J 0
(-4150 -2375);
DISPLAY 0.404255 (-4150 -2375);
FORCEPROP 1 LAST PACK_TYPE 0402LF
J 0
(-4450 -2325);
DISPLAY 0.319149 (-4450 -2325);
FORCEPROP 1 LAST $LOCATION R1022
J 0
(-4575 -2375);
DISPLAY 0.510638 (-4575 -2375);
FORCEPROP 1 LASTPIN (-4475 -2375) $PN 1
J 0
(-4463 -2363);
DISPLAY 0.787234 (-4463 -2363);
FORCEPROP 1 LASTPIN (-4275 -2375) $PN 2
J 0
(-4313 -2363);
DISPLAY 0.787234 (-4313 -2363);
FORCEPROP 2 LAST CDS_LIB pure_quanta
J 0
(-4375 -2375);
PAINT MONO (-4375 -2375);
DISPLAY INVISIBLE (-4375 -2375);
FORCEPROP 1 LAST PATH I28
J 0
(-4425 -2225);
DISPLAY 0.978723 (-4425 -2225);
PAINT WHITE (-4425 -2225);
DISPLAY INVISIBLE (-4425 -2225);
FORCEPROP 2 LAST CDS_LOCATION R1022
J 0
(-4425 -2175);
DISPLAY 1.021277 (-4425 -2175);
DISPLAY INVISIBLE (-4425 -2175);
FORCEPROP 2 LAST $SEC 1
J 0
(-4425 -2175);
DISPLAY 0.680851 (-4425 -2175);
PAINT MONO (-4425 -2175);
DISPLAY INVISIBLE (-4425 -2175);
FORCEPROP 2 LAST CDS_SEC 1
J 0
(-4425 -2175);
DISPLAY 1.021277 (-4425 -2175);
DISPLAY INVISIBLE (-4425 -2175);
FORCEADD Q_RES..1
(-4375 -1425);
FORCEPROP 1 LAST PART_NUMBER CS00002JB13
J 0
(-4450 -1400);
DISPLAY 0.319149 (-4450 -1400);
DISPLAY INVISIBLE (-4450 -1400);
FORCEPROP 1 LAST TOLERANCE 5%
J 0
(-4200 -1425);
DISPLAY 0.404255 (-4200 -1425);
FORCEPROP 1 LAST VALUE 0
J 2
(-4225 -1425);
DISPLAY 0.404255 (-4225 -1425);
FORCEPROP 1 LAST MATERIAL CHIP
J 0
(-4150 -1425);
DISPLAY 0.404255 (-4150 -1425);
FORCEPROP 1 LAST PACK_TYPE 0402LF
J 0
(-4450 -1375);
DISPLAY 0.319149 (-4450 -1375);
FORCEPROP 1 LAST WATTAGE 1/16W
J 2
(-4250 -1375);
DISPLAY 0.319149 (-4250 -1375);
FORCEPROP 1 LAST $LOCATION R1021
J 0
(-4575 -1425);
DISPLAY 0.510638 (-4575 -1425);
FORCEPROP 1 LASTPIN (-4475 -1425) $PN 1
J 0
(-4463 -1413);
DISPLAY 0.787234 (-4463 -1413);
FORCEPROP 1 LASTPIN (-4275 -1425) $PN 2
J 0
(-4313 -1413);
DISPLAY 0.787234 (-4313 -1413);
FORCEPROP 2 LAST CDS_LIB pure_quanta
J 0
(-4375 -1425);
PAINT MONO (-4375 -1425);
DISPLAY INVISIBLE (-4375 -1425);
FORCEPROP 1 LAST PATH I29
J 0
(-4425 -1275);
DISPLAY 0.978723 (-4425 -1275);
PAINT WHITE (-4425 -1275);
DISPLAY INVISIBLE (-4425 -1275);
FORCEPROP 2 LAST CDS_LOCATION R1021
J 0
(-4425 -1225);
DISPLAY 1.021277 (-4425 -1225);
DISPLAY INVISIBLE (-4425 -1225);
FORCEPROP 2 LAST $SEC 1
J 0
(-4425 -1225);
DISPLAY 0.680851 (-4425 -1225);
PAINT MONO (-4425 -1225);
DISPLAY INVISIBLE (-4425 -1225);
FORCEPROP 2 LAST CDS_SEC 1
J 0
(-4425 -1225);
DISPLAY 1.021277 (-4425 -1225);
DISPLAY INVISIBLE (-4425 -1225);
FORCEADD OFFPAGE..1
(-7475 -2900);
FORCEPROP 2 LAST $XR0 179 
J 0
(-7727 -2900);
DISPLAY 0.638298 (-7727 -2900);
PAINT MONO (-7727 -2900);
FORCEPROP 1 LAST COMMENT_BODY TRUE
J 0
(-7350 -3000);
DISPLAY 0.872340 (-7350 -3000);
PAINT GREEN (-7350 -3000);
DISPLAY INVISIBLE (-7350 -3000);
FORCEPROP 1 LAST OFFPAGE TRUE
J 0
(-7150 -3025);
DISPLAY 0.872340 (-7150 -3025);
DISPLAY INVISIBLE (-7150 -3025);
FORCEPROP 2 LAST CDS_LIB standard
J 0
(-7475 -2900);
PAINT MONO (-7475 -2900);
DISPLAY INVISIBLE (-7475 -2900);
FORCEPROP 2 LAST PATH I3
J 0
(-7725 -2850);
DISPLAY 1.021277 (-7725 -2850);
DISPLAY INVISIBLE (-7725 -2850);
FORCEADD Q_RES..1
(-4375 -1075);
FORCEPROP 1 LAST PART_NUMBER CS00002JB13
J 0
(-4450 -1050);
DISPLAY 0.319149 (-4450 -1050);
DISPLAY INVISIBLE (-4450 -1050);
FORCEPROP 1 LAST WATTAGE 1/16W
J 2
(-4250 -1025);
DISPLAY 0.319149 (-4250 -1025);
FORCEPROP 1 LAST PACK_TYPE 0402LF
J 0
(-4450 -1025);
DISPLAY 0.319149 (-4450 -1025);
FORCEPROP 1 LAST MATERIAL CHIP
J 0
(-4150 -1075);
DISPLAY 0.404255 (-4150 -1075);
FORCEPROP 1 LAST TOLERANCE 5%
J 0
(-4200 -1075);
DISPLAY 0.404255 (-4200 -1075);
FORCEPROP 1 LAST VALUE 0
J 2
(-4225 -1075);
DISPLAY 0.404255 (-4225 -1075);
FORCEPROP 1 LAST $LOCATION R1020
J 0
(-4575 -1075);
DISPLAY 0.510638 (-4575 -1075);
FORCEPROP 1 LASTPIN (-4475 -1075) $PN 1
J 0
(-4463 -1063);
DISPLAY 0.787234 (-4463 -1063);
FORCEPROP 1 LASTPIN (-4275 -1075) $PN 2
J 0
(-4313 -1063);
DISPLAY 0.787234 (-4313 -1063);
FORCEPROP 2 LAST CDS_LIB pure_quanta
J 0
(-4375 -1075);
PAINT MONO (-4375 -1075);
DISPLAY INVISIBLE (-4375 -1075);
FORCEPROP 1 LAST PATH I30
J 0
(-4425 -925);
DISPLAY 0.978723 (-4425 -925);
PAINT WHITE (-4425 -925);
DISPLAY INVISIBLE (-4425 -925);
FORCEPROP 2 LAST CDS_LOCATION R1020
J 0
(-4425 -875);
DISPLAY 1.021277 (-4425 -875);
DISPLAY INVISIBLE (-4425 -875);
FORCEPROP 2 LAST $SEC 1
J 0
(-4425 -875);
DISPLAY 0.680851 (-4425 -875);
PAINT MONO (-4425 -875);
DISPLAY INVISIBLE (-4425 -875);
FORCEPROP 2 LAST CDS_SEC 1
J 0
(-4425 -875);
DISPLAY 1.021277 (-4425 -875);
DISPLAY INVISIBLE (-4425 -875);
FORCEADD OFFPAGE..2
(-4175 -350);
FORCEPROP 2 LAST $XR0 153 
J 0
(-3986 -350);
DISPLAY 0.638298 (-3986 -350);
PAINT MONO (-3986 -350);
FORCEPROP 1 LAST COMMENT_BODY TRUE
J 0
(-4220 -445);
DISPLAY 0.872340 (-4220 -445);
PAINT GREEN (-4220 -445);
DISPLAY INVISIBLE (-4220 -445);
FORCEPROP 1 LAST OFFPAGE TRUE
J 0
(-3850 -475);
DISPLAY 0.872340 (-3850 -475);
DISPLAY INVISIBLE (-3850 -475);
FORCEPROP 2 LAST CDS_LIB standard
J 0
(-4175 -350);
DISPLAY INVISIBLE (-4175 -350);
FORCEPROP 2 LAST PATH I31
J 0
(-3975 -300);
DISPLAY 1.021277 (-3975 -300);
DISPLAY INVISIBLE (-3975 -300);
FORCEADD OFFPAGE..2
(-4175 -200);
FORCEPROP 2 LAST $XR0 153 
J 0
(-3986 -200);
DISPLAY 0.638298 (-3986 -200);
PAINT MONO (-3986 -200);
FORCEPROP 1 LAST COMMENT_BODY TRUE
J 0
(-4220 -295);
DISPLAY 0.872340 (-4220 -295);
PAINT GREEN (-4220 -295);
DISPLAY INVISIBLE (-4220 -295);
FORCEPROP 1 LAST OFFPAGE TRUE
J 0
(-3850 -325);
DISPLAY 0.872340 (-3850 -325);
DISPLAY INVISIBLE (-3850 -325);
FORCEPROP 2 LAST CDS_LIB standard
J 0
(-4175 -200);
DISPLAY INVISIBLE (-4175 -200);
FORCEPROP 2 LAST PATH I32
J 0
(-3975 -150);
DISPLAY 1.021277 (-3975 -150);
DISPLAY INVISIBLE (-3975 -150);
FORCEADD OFFPAGE..2
(-3075 -2725);
FORCEPROP 2 LAST $XR0 44 
J 0
(-2886 -2725);
DISPLAY 0.638298 (-2886 -2725);
PAINT MONO (-2886 -2725);
FORCEPROP 1 LAST OFFPAGE TRUE
J 0
(-2750 -2850);
DISPLAY 0.872340 (-2750 -2850);
DISPLAY INVISIBLE (-2750 -2850);
FORCEPROP 1 LAST COMMENT_BODY TRUE
J 0
(-3120 -2820);
DISPLAY 0.872340 (-3120 -2820);
PAINT GREEN (-3120 -2820);
DISPLAY INVISIBLE (-3120 -2820);
FORCEPROP 2 LAST CDS_LIB standard
J 0
(-3075 -2725);
PAINT MONO (-3075 -2725);
DISPLAY INVISIBLE (-3075 -2725);
FORCEPROP 2 LAST PATH I33
J 0
(-2875 -2675);
DISPLAY 1.021277 (-2875 -2675);
DISPLAY INVISIBLE (-2875 -2675);
FORCEADD OFFPAGE..2
(-3075 -2375);
FORCEPROP 2 LAST $XR0 44 
J 0
(-2886 -2375);
DISPLAY 0.638298 (-2886 -2375);
PAINT MONO (-2886 -2375);
FORCEPROP 2 LAST CDS_LIB standard
J 0
(-3075 -2375);
PAINT MONO (-3075 -2375);
DISPLAY INVISIBLE (-3075 -2375);
FORCEPROP 1 LAST COMMENT_BODY TRUE
J 0
(-3120 -2470);
DISPLAY 0.872340 (-3120 -2470);
PAINT GREEN (-3120 -2470);
DISPLAY INVISIBLE (-3120 -2470);
FORCEPROP 1 LAST OFFPAGE TRUE
J 0
(-2750 -2500);
DISPLAY 0.872340 (-2750 -2500);
DISPLAY INVISIBLE (-2750 -2500);
FORCEPROP 2 LAST PATH I34
J 0
(-2875 -2325);
DISPLAY 1.021277 (-2875 -2325);
DISPLAY INVISIBLE (-2875 -2325);
FORCEADD OFFPAGE..2
(-3075 -1425);
FORCEPROP 2 LAST $XR0 13 
J 0
(-2886 -1425);
DISPLAY 0.638298 (-2886 -1425);
PAINT MONO (-2886 -1425);
FORCEPROP 2 LAST CDS_LIB standard
J 0
(-3075 -1425);
PAINT MONO (-3075 -1425);
DISPLAY INVISIBLE (-3075 -1425);
FORCEPROP 1 LAST COMMENT_BODY TRUE
J 0
(-3120 -1520);
DISPLAY 0.872340 (-3120 -1520);
PAINT GREEN (-3120 -1520);
DISPLAY INVISIBLE (-3120 -1520);
FORCEPROP 1 LAST OFFPAGE TRUE
J 0
(-2750 -1550);
DISPLAY 0.872340 (-2750 -1550);
DISPLAY INVISIBLE (-2750 -1550);
FORCEPROP 2 LAST PATH I35
J 0
(-2875 -1375);
DISPLAY 1.021277 (-2875 -1375);
DISPLAY INVISIBLE (-2875 -1375);
FORCEADD OFFPAGE..2
(-3075 -1075);
FORCEPROP 2 LAST $XR0 13 
J 0
(-2886 -1075);
DISPLAY 0.638298 (-2886 -1075);
PAINT MONO (-2886 -1075);
FORCEPROP 1 LAST OFFPAGE TRUE
J 0
(-2750 -1200);
DISPLAY 0.872340 (-2750 -1200);
DISPLAY INVISIBLE (-2750 -1200);
FORCEPROP 1 LAST COMMENT_BODY TRUE
J 0
(-3120 -1170);
DISPLAY 0.872340 (-3120 -1170);
PAINT GREEN (-3120 -1170);
DISPLAY INVISIBLE (-3120 -1170);
FORCEPROP 2 LAST CDS_LIB standard
J 0
(-3075 -1075);
PAINT MONO (-3075 -1075);
DISPLAY INVISIBLE (-3075 -1075);
FORCEPROP 2 LAST PATH I36
J 0
(-2875 -1025);
DISPLAY 1.021277 (-2875 -1025);
DISPLAY INVISIBLE (-2875 -1025);
FORCEADD OFFPAGE..1
(-7450 200);
FORCEPROP 2 LAST $XR0 206 
J 0
(-7732 200);
DISPLAY 0.638298 (-7732 200);
PAINT MONO (-7732 200);
FORCEPROP 2 LAST CDS_LIB standard
J 0
(-7450 200);
DISPLAY INVISIBLE (-7450 200);
FORCEPROP 1 LAST OFFPAGE TRUE
J 0
(-7125 75);
DISPLAY 0.872340 (-7125 75);
DISPLAY INVISIBLE (-7125 75);
FORCEPROP 1 LAST COMMENT_BODY TRUE
J 0
(-7325 100);
DISPLAY 0.872340 (-7325 100);
PAINT GREEN (-7325 100);
DISPLAY INVISIBLE (-7325 100);
FORCEPROP 2 LAST PATH I37
J 0
(-7725 250);
DISPLAY 1.021277 (-7725 250);
DISPLAY INVISIBLE (-7725 250);
FORCEADD OFFPAGE..1
(-7450 50);
FORCEPROP 2 LAST $XR0 206 
J 0
(-7732 50);
DISPLAY 0.638298 (-7732 50);
PAINT MONO (-7732 50);
FORCEPROP 2 LAST CDS_LIB standard
J 0
(-7450 50);
DISPLAY INVISIBLE (-7450 50);
FORCEPROP 1 LAST OFFPAGE TRUE
J 0
(-7125 -75);
DISPLAY 0.872340 (-7125 -75);
DISPLAY INVISIBLE (-7125 -75);
FORCEPROP 1 LAST COMMENT_BODY TRUE
J 0
(-7325 -50);
DISPLAY 0.872340 (-7325 -50);
PAINT GREEN (-7325 -50);
DISPLAY INVISIBLE (-7325 -50);
FORCEPROP 2 LAST PATH I38
J 0
(-7725 100);
DISPLAY 1.021277 (-7725 100);
DISPLAY INVISIBLE (-7725 100);
FORCEADD OFFPAGE..1
(-7450 450);
FORCEPROP 2 LAST $XR0 206 
J 0
(-7732 450);
DISPLAY 0.638298 (-7732 450);
PAINT MONO (-7732 450);
FORCEPROP 2 LAST CDS_LIB standard
J 0
(-7450 450);
DISPLAY INVISIBLE (-7450 450);
FORCEPROP 1 LAST OFFPAGE TRUE
J 0
(-7125 325);
DISPLAY 0.872340 (-7125 325);
DISPLAY INVISIBLE (-7125 325);
FORCEPROP 1 LAST COMMENT_BODY TRUE
J 0
(-7325 350);
DISPLAY 0.872340 (-7325 350);
PAINT GREEN (-7325 350);
DISPLAY INVISIBLE (-7325 350);
FORCEPROP 2 LAST PATH I39
J 0
(-7725 500);
DISPLAY 1.021277 (-7725 500);
DISPLAY INVISIBLE (-7725 500);
FORCEADD OFFPAGE..1
(-7475 -2725);
FORCEPROP 2 LAST $XR0 208 
J 0
(-7727 -2725);
DISPLAY 0.638298 (-7727 -2725);
PAINT MONO (-7727 -2725);
FORCEPROP 1 LAST COMMENT_BODY TRUE
J 0
(-7350 -2825);
DISPLAY 0.872340 (-7350 -2825);
PAINT GREEN (-7350 -2825);
DISPLAY INVISIBLE (-7350 -2825);
FORCEPROP 1 LAST OFFPAGE TRUE
J 0
(-7150 -2850);
DISPLAY 0.872340 (-7150 -2850);
DISPLAY INVISIBLE (-7150 -2850);
FORCEPROP 2 LAST CDS_LIB standard
J 0
(-7475 -2725);
PAINT MONO (-7475 -2725);
DISPLAY INVISIBLE (-7475 -2725);
FORCEPROP 2 LAST PATH I4
J 0
(-7725 -2675);
DISPLAY 1.021277 (-7725 -2675);
DISPLAY INVISIBLE (-7725 -2675);
FORCEADD OFFPAGE..1
(-7450 600);
FORCEPROP 2 LAST $XR0 206 
J 0
(-7732 600);
DISPLAY 0.638298 (-7732 600);
PAINT MONO (-7732 600);
FORCEPROP 2 LAST CDS_LIB standard
J 0
(-7450 600);
DISPLAY INVISIBLE (-7450 600);
FORCEPROP 1 LAST OFFPAGE TRUE
J 0
(-7125 475);
DISPLAY 0.872340 (-7125 475);
DISPLAY INVISIBLE (-7125 475);
FORCEPROP 1 LAST COMMENT_BODY TRUE
J 0
(-7325 500);
DISPLAY 0.872340 (-7325 500);
PAINT GREEN (-7325 500);
DISPLAY INVISIBLE (-7325 500);
FORCEPROP 2 LAST PATH I40
J 0
(-7725 650);
DISPLAY 1.021277 (-7725 650);
DISPLAY INVISIBLE (-7725 650);
FORCEADD OFFPAGE..1
(-7450 850);
FORCEPROP 2 LAST $XR0 206 
J 0
(-7732 850);
DISPLAY 0.638298 (-7732 850);
PAINT MONO (-7732 850);
FORCEPROP 2 LAST CDS_LIB standard
J 0
(-7450 850);
DISPLAY INVISIBLE (-7450 850);
FORCEPROP 1 LAST OFFPAGE TRUE
J 0
(-7125 725);
DISPLAY 0.872340 (-7125 725);
DISPLAY INVISIBLE (-7125 725);
FORCEPROP 1 LAST COMMENT_BODY TRUE
J 0
(-7325 750);
DISPLAY 0.872340 (-7325 750);
PAINT GREEN (-7325 750);
DISPLAY INVISIBLE (-7325 750);
FORCEPROP 2 LAST PATH I41
J 0
(-7725 900);
DISPLAY 1.021277 (-7725 900);
DISPLAY INVISIBLE (-7725 900);
FORCEADD OFFPAGE..1
(-7450 1000);
FORCEPROP 2 LAST $XR0 206 
J 0
(-7732 1000);
DISPLAY 0.638298 (-7732 1000);
PAINT MONO (-7732 1000);
FORCEPROP 2 LAST CDS_LIB standard
J 0
(-7450 1000);
DISPLAY INVISIBLE (-7450 1000);
FORCEPROP 1 LAST OFFPAGE TRUE
J 0
(-7125 875);
DISPLAY 0.872340 (-7125 875);
DISPLAY INVISIBLE (-7125 875);
FORCEPROP 1 LAST COMMENT_BODY TRUE
J 0
(-7325 900);
DISPLAY 0.872340 (-7325 900);
PAINT GREEN (-7325 900);
DISPLAY INVISIBLE (-7325 900);
FORCEPROP 2 LAST PATH I42
J 0
(-7725 1050);
DISPLAY 1.021277 (-7725 1050);
DISPLAY INVISIBLE (-7725 1050);
FORCEADD Q_RES..1
(-6025 50);
FORCEPROP 1 LAST PART_NUMBER CS02202FB02
J 0
(-5900 100);
DISPLAY 0.638298 (-5900 100);
DISPLAY INVISIBLE (-5900 100);
FORCEPROP 1 LAST TOLERANCE 1%
J 0
(-5725 50);
DISPLAY 0.787234 (-5725 50);
FORCEPROP 1 LAST PACK_TYPE 0402LF
J 0
(-5625 50);
DISPLAY 0.787234 (-5625 50);
FORCEPROP 1 LAST WATTAGE 1/16W
J 2
(-5550 150);
DISPLAY 0.638298 (-5550 150);
FORCEPROP 1 LAST MATERIAL CHIP
J 0
(-5900 150);
DISPLAY 0.638298 (-5900 150);
FORCEPROP 1 LAST VALUE 22
J 2
(-5750 50);
DISPLAY 0.787234 (-5750 50);
FORCEPROP 1 LAST $LOCATION R1274
J 0
(-6275 50);
DISPLAY 0.808511 (-6275 50);
FORCEPROP 1 LASTPIN (-6125 50) $PN 1
J 0
(-6113 62);
DISPLAY 0.787234 (-6113 62);
FORCEPROP 1 LASTPIN (-5925 50) $PN 2
J 0
(-5963 62);
DISPLAY 0.787234 (-5963 62);
FORCEPROP 2 LAST CDS_LIB pure_quanta
J 0
(-6025 50);
PAINT MONO (-6025 50);
DISPLAY INVISIBLE (-6025 50);
FORCEPROP 1 LAST PATH I43
J 0
(-6075 200);
DISPLAY 0.978723 (-6075 200);
PAINT WHITE (-6075 200);
DISPLAY INVISIBLE (-6075 200);
FORCEPROP 2 LAST CDS_LOCATION R1274
J 0
(-6075 250);
DISPLAY 1.021277 (-6075 250);
DISPLAY INVISIBLE (-6075 250);
FORCEPROP 2 LAST $SEC 1
J 0
(-6075 250);
DISPLAY 0.680851 (-6075 250);
PAINT MONO (-6075 250);
DISPLAY INVISIBLE (-6075 250);
FORCEPROP 2 LAST CDS_SEC 1
J 0
(-6075 250);
DISPLAY 1.021277 (-6075 250);
DISPLAY INVISIBLE (-6075 250);
FORCEADD Q_RES..1
(-6025 200);
FORCEPROP 1 LAST PART_NUMBER CS02202FB02
J 0
(-5900 250);
DISPLAY 0.638298 (-5900 250);
DISPLAY INVISIBLE (-5900 250);
FORCEPROP 1 LAST WATTAGE 1/16W
J 2
(-5550 300);
DISPLAY 0.638298 (-5550 300);
FORCEPROP 1 LAST MATERIAL CHIP
J 0
(-5900 300);
DISPLAY 0.638298 (-5900 300);
FORCEPROP 1 LAST PACK_TYPE 0402LF
J 0
(-5625 200);
DISPLAY 0.787234 (-5625 200);
FORCEPROP 1 LAST TOLERANCE 1%
J 0
(-5725 200);
DISPLAY 0.787234 (-5725 200);
FORCEPROP 1 LAST VALUE 22
J 2
(-5750 200);
DISPLAY 0.787234 (-5750 200);
FORCEPROP 1 LAST $LOCATION R1273
J 0
(-6275 200);
DISPLAY 0.808511 (-6275 200);
FORCEPROP 1 LASTPIN (-6125 200) $PN 1
J 0
(-6113 212);
DISPLAY 0.787234 (-6113 212);
FORCEPROP 1 LASTPIN (-5925 200) $PN 2
J 0
(-5963 212);
DISPLAY 0.787234 (-5963 212);
FORCEPROP 2 LAST CDS_LIB pure_quanta
J 0
(-6025 200);
PAINT MONO (-6025 200);
DISPLAY INVISIBLE (-6025 200);
FORCEPROP 1 LAST PATH I44
J 0
(-6075 350);
DISPLAY 0.978723 (-6075 350);
PAINT WHITE (-6075 350);
DISPLAY INVISIBLE (-6075 350);
FORCEPROP 2 LAST CDS_LOCATION R1273
J 0
(-6075 400);
DISPLAY 1.021277 (-6075 400);
DISPLAY INVISIBLE (-6075 400);
FORCEPROP 2 LAST $SEC 1
J 0
(-6075 400);
DISPLAY 0.680851 (-6075 400);
PAINT MONO (-6075 400);
DISPLAY INVISIBLE (-6075 400);
FORCEPROP 2 LAST CDS_SEC 1
J 0
(-6075 400);
DISPLAY 1.021277 (-6075 400);
DISPLAY INVISIBLE (-6075 400);
FORCEADD Q_RES..1
(-6025 450);
FORCEPROP 1 LAST PART_NUMBER CS02202FB02
J 0
(-5900 500);
DISPLAY 0.638298 (-5900 500);
DISPLAY INVISIBLE (-5900 500);
FORCEPROP 1 LAST TOLERANCE 1%
J 0
(-5725 450);
DISPLAY 0.787234 (-5725 450);
FORCEPROP 1 LAST VALUE 22
J 2
(-5750 450);
DISPLAY 0.787234 (-5750 450);
FORCEPROP 1 LAST WATTAGE 1/16W
J 2
(-5550 550);
DISPLAY 0.638298 (-5550 550);
FORCEPROP 1 LAST MATERIAL CHIP
J 0
(-5900 550);
DISPLAY 0.638298 (-5900 550);
FORCEPROP 1 LAST PACK_TYPE 0402LF
J 0
(-5625 450);
DISPLAY 0.787234 (-5625 450);
FORCEPROP 1 LAST $LOCATION R566
J 0
(-6275 450);
DISPLAY 0.808511 (-6275 450);
FORCEPROP 1 LASTPIN (-6125 450) $PN 1
J 0
(-6113 462);
DISPLAY 0.787234 (-6113 462);
FORCEPROP 1 LASTPIN (-5925 450) $PN 2
J 0
(-5963 462);
DISPLAY 0.787234 (-5963 462);
FORCEPROP 2 LAST CDS_LIB pure_quanta
J 0
(-6025 450);
PAINT MONO (-6025 450);
DISPLAY INVISIBLE (-6025 450);
FORCEPROP 1 LAST PATH I45
J 0
(-6075 600);
DISPLAY 0.978723 (-6075 600);
PAINT WHITE (-6075 600);
DISPLAY INVISIBLE (-6075 600);
FORCEPROP 2 LAST CDS_LOCATION R566
J 0
(-6075 650);
DISPLAY 1.021277 (-6075 650);
DISPLAY INVISIBLE (-6075 650);
FORCEPROP 2 LAST $SEC 1
J 0
(-6075 650);
DISPLAY 0.680851 (-6075 650);
PAINT MONO (-6075 650);
DISPLAY INVISIBLE (-6075 650);
FORCEPROP 2 LAST CDS_SEC 1
J 0
(-6075 650);
DISPLAY 1.021277 (-6075 650);
DISPLAY INVISIBLE (-6075 650);
FORCEADD Q_RES..1
(-6025 600);
FORCEPROP 1 LAST PART_NUMBER CS02202FB02
J 0
(-5900 650);
DISPLAY 0.638298 (-5900 650);
DISPLAY INVISIBLE (-5900 650);
FORCEPROP 1 LAST MATERIAL CHIP
J 0
(-5900 700);
DISPLAY 0.638298 (-5900 700);
FORCEPROP 1 LAST PACK_TYPE 0402LF
J 0
(-5625 600);
DISPLAY 0.787234 (-5625 600);
FORCEPROP 1 LAST VALUE 22
J 2
(-5750 600);
DISPLAY 0.787234 (-5750 600);
FORCEPROP 1 LAST TOLERANCE 1%
J 0
(-5725 600);
DISPLAY 0.787234 (-5725 600);
FORCEPROP 1 LAST WATTAGE 1/16W
J 2
(-5550 700);
DISPLAY 0.638298 (-5550 700);
FORCEPROP 1 LAST $LOCATION R565
J 0
(-6275 600);
DISPLAY 0.808511 (-6275 600);
FORCEPROP 1 LASTPIN (-6125 600) $PN 1
J 0
(-6113 612);
DISPLAY 0.787234 (-6113 612);
FORCEPROP 1 LASTPIN (-5925 600) $PN 2
J 0
(-5963 612);
DISPLAY 0.787234 (-5963 612);
FORCEPROP 2 LAST CDS_LIB pure_quanta
J 0
(-6025 600);
PAINT MONO (-6025 600);
DISPLAY INVISIBLE (-6025 600);
FORCEPROP 1 LAST PATH I46
J 0
(-6075 750);
DISPLAY 0.978723 (-6075 750);
PAINT WHITE (-6075 750);
DISPLAY INVISIBLE (-6075 750);
FORCEPROP 2 LAST CDS_LOCATION R565
J 0
(-6075 800);
DISPLAY 1.021277 (-6075 800);
DISPLAY INVISIBLE (-6075 800);
FORCEPROP 2 LAST $SEC 1
J 0
(-6075 800);
DISPLAY 0.680851 (-6075 800);
PAINT MONO (-6075 800);
DISPLAY INVISIBLE (-6075 800);
FORCEPROP 2 LAST CDS_SEC 1
J 0
(-6075 800);
DISPLAY 1.021277 (-6075 800);
DISPLAY INVISIBLE (-6075 800);
FORCEADD Q_RES..1
(-6025 850);
FORCEPROP 1 LAST PART_NUMBER CS02202FB02
J 0
(-5900 900);
DISPLAY 0.638298 (-5900 900);
DISPLAY INVISIBLE (-5900 900);
FORCEPROP 1 LAST PACK_TYPE 0402LF
J 0
(-5625 850);
DISPLAY 0.787234 (-5625 850);
FORCEPROP 1 LAST WATTAGE 1/16W
J 2
(-5550 950);
DISPLAY 0.638298 (-5550 950);
FORCEPROP 1 LAST VALUE 22
J 2
(-5750 850);
DISPLAY 0.787234 (-5750 850);
FORCEPROP 1 LAST TOLERANCE 1%
J 0
(-5725 850);
DISPLAY 0.787234 (-5725 850);
FORCEPROP 1 LAST MATERIAL CHIP
J 0
(-5900 950);
DISPLAY 0.638298 (-5900 950);
FORCEPROP 1 LAST $LOCATION R564
J 0
(-6275 850);
DISPLAY 0.808511 (-6275 850);
FORCEPROP 1 LASTPIN (-6125 850) $PN 1
J 0
(-6113 862);
DISPLAY 0.787234 (-6113 862);
FORCEPROP 1 LASTPIN (-5925 850) $PN 2
J 0
(-5963 862);
DISPLAY 0.787234 (-5963 862);
FORCEPROP 2 LAST CDS_LIB pure_quanta
J 0
(-6025 850);
PAINT MONO (-6025 850);
DISPLAY INVISIBLE (-6025 850);
FORCEPROP 1 LAST PATH I47
J 0
(-6075 1000);
DISPLAY 0.978723 (-6075 1000);
PAINT WHITE (-6075 1000);
DISPLAY INVISIBLE (-6075 1000);
FORCEPROP 2 LAST CDS_LOCATION R564
J 0
(-6075 1050);
DISPLAY 1.021277 (-6075 1050);
DISPLAY INVISIBLE (-6075 1050);
FORCEPROP 2 LAST $SEC 1
J 0
(-6075 1050);
DISPLAY 0.680851 (-6075 1050);
PAINT MONO (-6075 1050);
DISPLAY INVISIBLE (-6075 1050);
FORCEPROP 2 LAST CDS_SEC 1
J 0
(-6075 1050);
DISPLAY 1.021277 (-6075 1050);
DISPLAY INVISIBLE (-6075 1050);
FORCEADD Q_RES..1
(-6025 1000);
FORCEPROP 1 LAST PART_NUMBER CS02202FB02
J 0
(-5900 1050);
DISPLAY 0.638298 (-5900 1050);
DISPLAY INVISIBLE (-5900 1050);
FORCEPROP 1 LAST PACK_TYPE 0402LF
J 0
(-5625 1000);
DISPLAY 0.787234 (-5625 1000);
FORCEPROP 1 LAST VALUE 22
J 2
(-5750 1000);
DISPLAY 0.787234 (-5750 1000);
FORCEPROP 1 LAST TOLERANCE 1%
J 0
(-5725 1000);
DISPLAY 0.787234 (-5725 1000);
FORCEPROP 1 LAST MATERIAL CHIP
J 0
(-5900 1100);
DISPLAY 0.638298 (-5900 1100);
FORCEPROP 1 LAST WATTAGE 1/16W
J 2
(-5550 1100);
DISPLAY 0.638298 (-5550 1100);
FORCEPROP 1 LAST $LOCATION R563
J 0
(-6275 1000);
DISPLAY 0.808511 (-6275 1000);
FORCEPROP 1 LASTPIN (-6125 1000) $PN 1
J 0
(-6113 1012);
DISPLAY 0.787234 (-6113 1012);
FORCEPROP 1 LASTPIN (-5925 1000) $PN 2
J 0
(-5963 1012);
DISPLAY 0.787234 (-5963 1012);
FORCEPROP 2 LAST CDS_LIB pure_quanta
J 0
(-6025 1000);
PAINT MONO (-6025 1000);
DISPLAY INVISIBLE (-6025 1000);
FORCEPROP 1 LAST PATH I48
J 0
(-6075 1150);
DISPLAY 0.978723 (-6075 1150);
PAINT WHITE (-6075 1150);
DISPLAY INVISIBLE (-6075 1150);
FORCEPROP 2 LAST CDS_LOCATION R563
J 0
(-6075 1200);
DISPLAY 1.021277 (-6075 1200);
DISPLAY INVISIBLE (-6075 1200);
FORCEPROP 2 LAST $SEC 1
J 0
(-6075 1200);
DISPLAY 0.680851 (-6075 1200);
PAINT MONO (-6075 1200);
DISPLAY INVISIBLE (-6075 1200);
FORCEPROP 2 LAST CDS_SEC 1
J 0
(-6075 1200);
DISPLAY 1.021277 (-6075 1200);
DISPLAY INVISIBLE (-6075 1200);
FORCEADD OFFPAGE..2
(-4175 50);
FORCEPROP 2 LAST $XR0 153 
J 0
(-3986 50);
DISPLAY 0.638298 (-3986 50);
PAINT MONO (-3986 50);
FORCEPROP 1 LAST COMMENT_BODY TRUE
J 0
(-4220 -45);
DISPLAY 0.872340 (-4220 -45);
PAINT GREEN (-4220 -45);
DISPLAY INVISIBLE (-4220 -45);
FORCEPROP 1 LAST OFFPAGE TRUE
J 0
(-3850 -75);
DISPLAY 0.872340 (-3850 -75);
DISPLAY INVISIBLE (-3850 -75);
FORCEPROP 2 LAST CDS_LIB standard
J 0
(-4175 50);
DISPLAY INVISIBLE (-4175 50);
FORCEPROP 2 LAST PATH I49
J 0
(-3975 100);
DISPLAY 1.021277 (-3975 100);
DISPLAY INVISIBLE (-3975 100);
FORCEADD OFFPAGE..1
(-7475 -2550);
FORCEPROP 2 LAST $XR0 179 
J 0
(-7727 -2550);
DISPLAY 0.638298 (-7727 -2550);
PAINT MONO (-7727 -2550);
FORCEPROP 2 LAST CDS_LIB standard
J 0
(-7475 -2550);
PAINT MONO (-7475 -2550);
DISPLAY INVISIBLE (-7475 -2550);
FORCEPROP 1 LAST OFFPAGE TRUE
J 0
(-7150 -2675);
DISPLAY 0.872340 (-7150 -2675);
DISPLAY INVISIBLE (-7150 -2675);
FORCEPROP 1 LAST COMMENT_BODY TRUE
J 0
(-7350 -2650);
DISPLAY 0.872340 (-7350 -2650);
PAINT GREEN (-7350 -2650);
DISPLAY INVISIBLE (-7350 -2650);
FORCEPROP 2 LAST PATH I5
J 0
(-7725 -2500);
DISPLAY 1.021277 (-7725 -2500);
DISPLAY INVISIBLE (-7725 -2500);
FORCEADD OFFPAGE..2
(-4175 200);
FORCEPROP 2 LAST $XR0 153 
J 0
(-3986 200);
DISPLAY 0.638298 (-3986 200);
PAINT MONO (-3986 200);
FORCEPROP 1 LAST COMMENT_BODY TRUE
J 0
(-4220 105);
DISPLAY 0.872340 (-4220 105);
PAINT GREEN (-4220 105);
DISPLAY INVISIBLE (-4220 105);
FORCEPROP 1 LAST OFFPAGE TRUE
J 0
(-3850 75);
DISPLAY 0.872340 (-3850 75);
DISPLAY INVISIBLE (-3850 75);
FORCEPROP 2 LAST CDS_LIB standard
J 0
(-4175 200);
DISPLAY INVISIBLE (-4175 200);
FORCEPROP 2 LAST PATH I50
J 0
(-3975 250);
DISPLAY 1.021277 (-3975 250);
DISPLAY INVISIBLE (-3975 250);
FORCEADD OFFPAGE..2
(-4175 450);
FORCEPROP 2 LAST $XR0 153 
J 0
(-3986 450);
DISPLAY 0.638298 (-3986 450);
PAINT MONO (-3986 450);
FORCEPROP 1 LAST COMMENT_BODY TRUE
J 0
(-4220 355);
DISPLAY 0.872340 (-4220 355);
PAINT GREEN (-4220 355);
DISPLAY INVISIBLE (-4220 355);
FORCEPROP 1 LAST OFFPAGE TRUE
J 0
(-3850 325);
DISPLAY 0.872340 (-3850 325);
DISPLAY INVISIBLE (-3850 325);
FORCEPROP 2 LAST CDS_LIB standard
J 0
(-4175 450);
DISPLAY INVISIBLE (-4175 450);
FORCEPROP 2 LAST PATH I51
J 0
(-3975 500);
DISPLAY 1.021277 (-3975 500);
DISPLAY INVISIBLE (-3975 500);
FORCEADD OFFPAGE..2
(-4175 600);
FORCEPROP 2 LAST $XR0 153 
J 0
(-3986 600);
DISPLAY 0.638298 (-3986 600);
PAINT MONO (-3986 600);
FORCEPROP 1 LAST COMMENT_BODY TRUE
J 0
(-4220 505);
DISPLAY 0.872340 (-4220 505);
PAINT GREEN (-4220 505);
DISPLAY INVISIBLE (-4220 505);
FORCEPROP 1 LAST OFFPAGE TRUE
J 0
(-3850 475);
DISPLAY 0.872340 (-3850 475);
DISPLAY INVISIBLE (-3850 475);
FORCEPROP 2 LAST CDS_LIB standard
J 0
(-4175 600);
DISPLAY INVISIBLE (-4175 600);
FORCEPROP 2 LAST PATH I52
J 0
(-3975 650);
DISPLAY 1.021277 (-3975 650);
DISPLAY INVISIBLE (-3975 650);
FORCEADD OFFPAGE..2
(-4175 850);
FORCEPROP 2 LAST $XR0 153 
J 0
(-3986 850);
DISPLAY 0.638298 (-3986 850);
PAINT MONO (-3986 850);
FORCEPROP 1 LAST COMMENT_BODY TRUE
J 0
(-4220 755);
DISPLAY 0.872340 (-4220 755);
PAINT GREEN (-4220 755);
DISPLAY INVISIBLE (-4220 755);
FORCEPROP 1 LAST OFFPAGE TRUE
J 0
(-3850 725);
DISPLAY 0.872340 (-3850 725);
DISPLAY INVISIBLE (-3850 725);
FORCEPROP 2 LAST CDS_LIB standard
J 0
(-4175 850);
DISPLAY INVISIBLE (-4175 850);
FORCEPROP 2 LAST PATH I53
J 0
(-3975 900);
DISPLAY 1.021277 (-3975 900);
DISPLAY INVISIBLE (-3975 900);
FORCEADD OFFPAGE..2
(-4175 1000);
FORCEPROP 2 LAST $XR0 153 
J 0
(-3986 1000);
DISPLAY 0.638298 (-3986 1000);
PAINT MONO (-3986 1000);
FORCEPROP 1 LAST COMMENT_BODY TRUE
J 0
(-4220 905);
DISPLAY 0.872340 (-4220 905);
PAINT GREEN (-4220 905);
DISPLAY INVISIBLE (-4220 905);
FORCEPROP 1 LAST OFFPAGE TRUE
J 0
(-3850 875);
DISPLAY 0.872340 (-3850 875);
DISPLAY INVISIBLE (-3850 875);
FORCEPROP 2 LAST CDS_LIB standard
J 0
(-4175 1000);
DISPLAY INVISIBLE (-4175 1000);
FORCEPROP 2 LAST PATH I54
J 0
(-3975 1050);
DISPLAY 1.021277 (-3975 1050);
DISPLAY INVISIBLE (-3975 1050);
FORCEADD OFFPAGE..1
(-3100 850);
FORCEPROP 2 LAST $XR0 208 
J 0
(-3352 850);
DISPLAY 0.638298 (-3352 850);
PAINT MONO (-3352 850);
FORCEPROP 2 LAST CDS_LIB standard
J 0
(-3100 850);
DISPLAY INVISIBLE (-3100 850);
FORCEPROP 1 LAST OFFPAGE TRUE
J 0
(-2775 725);
DISPLAY 0.872340 (-2775 725);
DISPLAY INVISIBLE (-2775 725);
FORCEPROP 1 LAST COMMENT_BODY TRUE
J 0
(-2975 750);
DISPLAY 0.872340 (-2975 750);
PAINT GREEN (-2975 750);
DISPLAY INVISIBLE (-2975 750);
FORCEPROP 2 LAST PATH I55
J 0
(-3350 900);
DISPLAY 1.021277 (-3350 900);
DISPLAY INVISIBLE (-3350 900);
FORCEADD OFFPAGE..1
(-3100 1025);
FORCEPROP 2 LAST $XR0 208 
J 0
(-3352 1025);
DISPLAY 0.638298 (-3352 1025);
PAINT MONO (-3352 1025);
FORCEPROP 2 LAST CDS_LIB standard
J 0
(-3100 1025);
DISPLAY INVISIBLE (-3100 1025);
FORCEPROP 1 LAST OFFPAGE TRUE
J 0
(-2775 900);
DISPLAY 0.872340 (-2775 900);
DISPLAY INVISIBLE (-2775 900);
FORCEPROP 1 LAST COMMENT_BODY TRUE
J 0
(-2975 925);
DISPLAY 0.872340 (-2975 925);
PAINT GREEN (-2975 925);
DISPLAY INVISIBLE (-2975 925);
FORCEPROP 2 LAST PATH I56
J 0
(-3350 1075);
DISPLAY 1.021277 (-3350 1075);
DISPLAY INVISIBLE (-3350 1075);
FORCEADD Q_RES..1
(-1675 850);
FORCEPROP 1 LAST PART_NUMBER CS00002JB13
J 0
(-1550 900);
DISPLAY 0.638298 (-1550 900);
DISPLAY INVISIBLE (-1550 900);
FORCEPROP 1 LAST PACK_TYPE 0402LF
J 0
(-1275 850);
DISPLAY 0.787234 (-1275 850);
FORCEPROP 1 LAST VALUE 0
J 2
(-1400 850);
DISPLAY 0.787234 (-1400 850);
FORCEPROP 1 LAST WATTAGE 1/16W
J 2
(-1200 950);
DISPLAY 0.638298 (-1200 950);
FORCEPROP 1 LAST TOLERANCE 5%
J 0
(-1375 850);
DISPLAY 0.787234 (-1375 850);
FORCEPROP 1 LAST MATERIAL CHIP
J 0
(-1550 950);
DISPLAY 0.638298 (-1550 950);
FORCEPROP 1 LAST $LOCATION R554
J 0
(-1900 850);
DISPLAY 0.787234 (-1900 850);
FORCEPROP 1 LASTPIN (-1775 850) $PN 1
J 0
(-1763 862);
DISPLAY 0.787234 (-1763 862);
FORCEPROP 1 LASTPIN (-1575 850) $PN 2
J 0
(-1613 862);
DISPLAY 0.787234 (-1613 862);
FORCEPROP 2 LAST CDS_LIB pure_quanta
J 0
(-1675 850);
PAINT MONO (-1675 850);
DISPLAY INVISIBLE (-1675 850);
FORCEPROP 1 LAST PATH I57
J 0
(-1725 1000);
DISPLAY 0.978723 (-1725 1000);
PAINT WHITE (-1725 1000);
DISPLAY INVISIBLE (-1725 1000);
FORCEPROP 2 LAST CDS_LOCATION R554
J 0
(-1725 1050);
DISPLAY 1.021277 (-1725 1050);
DISPLAY INVISIBLE (-1725 1050);
FORCEPROP 2 LAST $SEC 1
J 0
(-1725 1050);
DISPLAY 0.680851 (-1725 1050);
PAINT MONO (-1725 1050);
DISPLAY INVISIBLE (-1725 1050);
FORCEPROP 2 LAST CDS_SEC 1
J 0
(-1725 1050);
DISPLAY 1.021277 (-1725 1050);
DISPLAY INVISIBLE (-1725 1050);
FORCEADD Q_RES..1
(-1675 1025);
FORCEPROP 1 LAST PART_NUMBER CS00002JB13
J 0
(-1550 1075);
DISPLAY 0.638298 (-1550 1075);
DISPLAY INVISIBLE (-1550 1075);
FORCEPROP 1 LAST VALUE 0
J 2
(-1400 1025);
DISPLAY 0.787234 (-1400 1025);
FORCEPROP 1 LAST TOLERANCE 5%
J 0
(-1375 1025);
DISPLAY 0.787234 (-1375 1025);
FORCEPROP 1 LAST WATTAGE 1/16W
J 2
(-1200 1125);
DISPLAY 0.638298 (-1200 1125);
FORCEPROP 1 LAST PACK_TYPE 0402LF
J 0
(-1275 1025);
DISPLAY 0.787234 (-1275 1025);
FORCEPROP 1 LAST MATERIAL CHIP
J 0
(-1550 1125);
DISPLAY 0.638298 (-1550 1125);
FORCEPROP 1 LAST $LOCATION R553
J 0
(-1900 1025);
DISPLAY 0.787234 (-1900 1025);
FORCEPROP 1 LASTPIN (-1775 1025) $PN 1
J 0
(-1763 1037);
DISPLAY 0.787234 (-1763 1037);
FORCEPROP 1 LASTPIN (-1575 1025) $PN 2
J 0
(-1613 1037);
DISPLAY 0.787234 (-1613 1037);
FORCEPROP 2 LAST CDS_LIB pure_quanta
J 0
(-1675 1025);
PAINT MONO (-1675 1025);
DISPLAY INVISIBLE (-1675 1025);
FORCEPROP 1 LAST PATH I58
J 0
(-1725 1175);
DISPLAY 0.978723 (-1725 1175);
PAINT WHITE (-1725 1175);
DISPLAY INVISIBLE (-1725 1175);
FORCEPROP 2 LAST CDS_LOCATION R553
J 0
(-1725 1225);
DISPLAY 1.021277 (-1725 1225);
DISPLAY INVISIBLE (-1725 1225);
FORCEPROP 2 LAST $SEC 1
J 0
(-1725 1225);
DISPLAY 0.680851 (-1725 1225);
PAINT MONO (-1725 1225);
DISPLAY INVISIBLE (-1725 1225);
FORCEPROP 2 LAST CDS_SEC 1
J 0
(-1725 1225);
DISPLAY 1.021277 (-1725 1225);
DISPLAY INVISIBLE (-1725 1225);
FORCEADD OFFPAGE..2
(175 850);
FORCEPROP 2 LAST $XR0 179 
J 0
(364 850);
DISPLAY 0.638298 (364 850);
PAINT MONO (364 850);
FORCEPROP 2 LAST CDS_LIB standard
J 0
(175 850);
DISPLAY INVISIBLE (175 850);
FORCEPROP 1 LAST OFFPAGE TRUE
J 0
(500 725);
DISPLAY 0.872340 (500 725);
DISPLAY INVISIBLE (500 725);
FORCEPROP 1 LAST COMMENT_BODY TRUE
J 0
(130 755);
DISPLAY 0.872340 (130 755);
PAINT GREEN (130 755);
DISPLAY INVISIBLE (130 755);
FORCEPROP 2 LAST PATH I59
J 0
(375 900);
DISPLAY 1.021277 (375 900);
DISPLAY INVISIBLE (375 900);
FORCEADD OFFPAGE..1
(-7475 -2375);
FORCEPROP 2 LAST $XR0 208 
J 0
(-7727 -2375);
DISPLAY 0.638298 (-7727 -2375);
PAINT MONO (-7727 -2375);
FORCEPROP 2 LAST CDS_LIB standard
J 0
(-7475 -2375);
PAINT MONO (-7475 -2375);
DISPLAY INVISIBLE (-7475 -2375);
FORCEPROP 1 LAST OFFPAGE TRUE
J 0
(-7150 -2500);
DISPLAY 0.872340 (-7150 -2500);
DISPLAY INVISIBLE (-7150 -2500);
FORCEPROP 1 LAST COMMENT_BODY TRUE
J 0
(-7350 -2475);
DISPLAY 0.872340 (-7350 -2475);
PAINT GREEN (-7350 -2475);
DISPLAY INVISIBLE (-7350 -2475);
FORCEPROP 2 LAST PATH I6
J 0
(-7725 -2325);
DISPLAY 1.021277 (-7725 -2325);
DISPLAY INVISIBLE (-7725 -2325);
FORCEADD OFFPAGE..2
(175 1025);
FORCEPROP 2 LAST $XR0 179 
J 0
(364 1025);
DISPLAY 0.638298 (364 1025);
PAINT MONO (364 1025);
FORCEPROP 2 LAST CDS_LIB standard
J 0
(175 1025);
DISPLAY INVISIBLE (175 1025);
FORCEPROP 1 LAST OFFPAGE TRUE
J 0
(500 900);
DISPLAY 0.872340 (500 900);
DISPLAY INVISIBLE (500 900);
FORCEPROP 1 LAST COMMENT_BODY TRUE
J 0
(130 930);
DISPLAY 0.872340 (130 930);
PAINT GREEN (130 930);
DISPLAY INVISIBLE (130 930);
FORCEPROP 2 LAST PATH I60
J 0
(375 1075);
DISPLAY 1.021277 (375 1075);
DISPLAY INVISIBLE (375 1075);
FORCEADD Q_RES..1
(-6125 -3825);
FORCEPROP 1 LAST PART_NUMBER CS00002JB13
J 0
(-6200 -3750);
DISPLAY 0.319149 (-6200 -3750);
DISPLAY INVISIBLE (-6200 -3750);
FORCEPROP 1 LAST WATTAGE 1/16W
J 2
(-6000 -3725);
DISPLAY 0.319149 (-6000 -3725);
FORCEPROP 1 LAST PACK_TYPE 0402LF
J 0
(-6200 -3725);
DISPLAY 0.319149 (-6200 -3725);
FORCEPROP 1 LAST VALUE 0
J 2
(-5975 -3825);
DISPLAY 0.404255 (-5975 -3825);
FORCEPROP 1 LAST TOLERANCE 5%
J 0
(-5950 -3825);
DISPLAY 0.404255 (-5950 -3825);
FORCEPROP 1 LAST MATERIAL CHIP
J 0
(-5900 -3825);
DISPLAY 0.404255 (-5900 -3825);
FORCEPROP 1 LAST $LOCATION R1011
J 0
(-6325 -3825);
DISPLAY 0.510638 (-6325 -3825);
FORCEPROP 1 LASTPIN (-6225 -3825) $PN 1
J 0
(-6213 -3813);
DISPLAY 0.787234 (-6213 -3813);
FORCEPROP 1 LASTPIN (-6025 -3825) $PN 2
J 0
(-6063 -3813);
DISPLAY 0.787234 (-6063 -3813);
FORCEPROP 2 LAST CDS_LIB pure_quanta
J 0
(-6125 -3825);
PAINT MONO (-6125 -3825);
DISPLAY INVISIBLE (-6125 -3825);
FORCEPROP 1 LAST PATH I7
J 0
(-6175 -3675);
DISPLAY 0.978723 (-6175 -3675);
PAINT WHITE (-6175 -3675);
DISPLAY INVISIBLE (-6175 -3675);
FORCEPROP 2 LAST CDS_LOCATION R1011
J 0
(-6175 -3625);
DISPLAY 1.021277 (-6175 -3625);
DISPLAY INVISIBLE (-6175 -3625);
FORCEPROP 2 LAST $SEC 1
J 0
(-6175 -3625);
DISPLAY 0.680851 (-6175 -3625);
PAINT MONO (-6175 -3625);
DISPLAY INVISIBLE (-6175 -3625);
FORCEPROP 2 LAST CDS_SEC 1
J 0
(-6175 -3625);
DISPLAY 1.021277 (-6175 -3625);
DISPLAY INVISIBLE (-6175 -3625);
FORCEADD Q_RES..1
(-6125 -3650);
FORCEPROP 1 LAST PART_NUMBER CS00002JB13
J 0
(-6200 -3575);
DISPLAY 0.319149 (-6200 -3575);
DISPLAY INVISIBLE (-6200 -3575);
FORCEPROP 1 LAST MATERIAL CHIP
J 0
(-5900 -3650);
DISPLAY 0.404255 (-5900 -3650);
FORCEPROP 1 LAST VALUE 0
J 2
(-5975 -3650);
DISPLAY 0.404255 (-5975 -3650);
FORCEPROP 1 LAST WATTAGE 1/16W
J 2
(-6000 -3550);
DISPLAY 0.319149 (-6000 -3550);
FORCEPROP 1 LAST PACK_TYPE 0402LF
J 0
(-6200 -3550);
DISPLAY 0.319149 (-6200 -3550);
FORCEPROP 1 LAST TOLERANCE 5%
J 0
(-5950 -3650);
DISPLAY 0.404255 (-5950 -3650);
FORCEPROP 1 LAST $LOCATION R1010
J 0
(-6325 -3650);
DISPLAY 0.510638 (-6325 -3650);
FORCEPROP 1 LASTPIN (-6225 -3650) $PN 1
J 0
(-6213 -3638);
DISPLAY 0.787234 (-6213 -3638);
FORCEPROP 1 LASTPIN (-6025 -3650) $PN 2
J 0
(-6063 -3638);
DISPLAY 0.787234 (-6063 -3638);
FORCEPROP 2 LAST CDS_LIB pure_quanta
J 0
(-6125 -3650);
PAINT MONO (-6125 -3650);
DISPLAY INVISIBLE (-6125 -3650);
FORCEPROP 1 LAST PATH I8
J 0
(-6175 -3500);
DISPLAY 0.978723 (-6175 -3500);
PAINT WHITE (-6175 -3500);
DISPLAY INVISIBLE (-6175 -3500);
FORCEPROP 2 LAST CDS_LOCATION R1010
J 0
(-6175 -3450);
DISPLAY 1.021277 (-6175 -3450);
DISPLAY INVISIBLE (-6175 -3450);
FORCEPROP 2 LAST $SEC 1
J 0
(-6175 -3450);
DISPLAY 0.680851 (-6175 -3450);
PAINT MONO (-6175 -3450);
DISPLAY INVISIBLE (-6175 -3450);
FORCEPROP 2 LAST CDS_SEC 1
J 0
(-6175 -3450);
DISPLAY 1.021277 (-6175 -3450);
DISPLAY INVISIBLE (-6175 -3450);
FORCEADD Q_RES..1
(-6100 -2900);
FORCEPROP 1 LAST PART_NUMBER CS00002JB13
J 0
(-6175 -2875);
DISPLAY 0.319149 (-6175 -2875);
DISPLAY INVISIBLE (-6175 -2875);
FORCEPROP 1 LAST PACK_TYPE 0402LF
J 0
(-6175 -2850);
DISPLAY 0.319149 (-6175 -2850);
FORCEPROP 1 LAST WATTAGE 1/16W
J 2
(-5975 -2850);
DISPLAY 0.319149 (-5975 -2850);
FORCEPROP 1 LAST VALUE 0
J 2
(-5950 -2900);
DISPLAY 0.404255 (-5950 -2900);
FORCEPROP 1 LAST TOLERANCE 5%
J 0
(-5925 -2900);
DISPLAY 0.404255 (-5925 -2900);
FORCEPROP 1 LAST MATERIAL EMPTY
J 0
(-5875 -2900);
DISPLAY 0.404255 (-5875 -2900);
PAINT RED (-5875 -2900);
FORCEPROP 1 LAST $LOCATION R1019
J 0
(-6300 -2900);
DISPLAY 0.510638 (-6300 -2900);
FORCEPROP 1 LASTPIN (-6200 -2900) $PN 1
J 0
(-6188 -2888);
DISPLAY 0.787234 (-6188 -2888);
FORCEPROP 1 LASTPIN (-6000 -2900) $PN 2
J 0
(-6038 -2888);
DISPLAY 0.787234 (-6038 -2888);
FORCEPROP 2 LAST CDS_LIB pure_quanta
J 0
(-6100 -2900);
PAINT MONO (-6100 -2900);
DISPLAY INVISIBLE (-6100 -2900);
FORCEPROP 1 LAST PATH I9
J 0
(-6150 -2750);
DISPLAY 0.978723 (-6150 -2750);
PAINT WHITE (-6150 -2750);
DISPLAY INVISIBLE (-6150 -2750);
FORCEPROP 2 LAST CDS_LOCATION R1019
J 0
(-6150 -2700);
DISPLAY 1.021277 (-6150 -2700);
DISPLAY INVISIBLE (-6150 -2700);
FORCEPROP 2 LAST $SEC 1
J 0
(-6150 -2700);
DISPLAY 0.680851 (-6150 -2700);
PAINT MONO (-6150 -2700);
DISPLAY INVISIBLE (-6150 -2700);
FORCEPROP 2 LAST CDS_SEC 1
J 0
(-6150 -2700);
DISPLAY 1.021277 (-6150 -2700);
DISPLAY INVISIBLE (-6150 -2700);
FORCEADD DNS..2
(-6095 -2905);
PAINT RED (-6095 -2905);
FORCEPROP 2 LAST CDS_LIB mstr_misc
J 0
(-6095 -2905);
PAINT MONO (-6095 -2905);
DISPLAY INVISIBLE (-6095 -2905);
FORCEPROP 1 LAST COMMENT_BODY TRUE
J 0
(-6095 -2905);
DISPLAY INVISIBLE (-6095 -2905);
FORCEADD DNS..2
(-6095 -2555);
PAINT RED (-6095 -2555);
FORCEPROP 1 LAST COMMENT_BODY TRUE
J 0
(-6095 -2555);
DISPLAY INVISIBLE (-6095 -2555);
FORCEPROP 2 LAST CDS_LIB mstr_misc
J 0
(-6095 -2555);
PAINT MONO (-6095 -2555);
DISPLAY INVISIBLE (-6095 -2555);
FORCEADD DNS..2
(-6095 -1605);
PAINT RED (-6095 -1605);
FORCEPROP 1 LAST COMMENT_BODY TRUE
J 0
(-6095 -1605);
DISPLAY INVISIBLE (-6095 -1605);
FORCEPROP 2 LAST CDS_LIB mstr_misc
J 0
(-6095 -1605);
PAINT MONO (-6095 -1605);
DISPLAY INVISIBLE (-6095 -1605);
FORCEADD DNS..2
(-6095 -1255);
PAINT RED (-6095 -1255);
FORCEPROP 2 LAST CDS_LIB mstr_misc
J 0
(-6095 -1255);
PAINT MONO (-6095 -1255);
DISPLAY INVISIBLE (-6095 -1255);
FORCEPROP 1 LAST COMMENT_BODY TRUE
J 0
(-6095 -1255);
DISPLAY INVISIBLE (-6095 -1255);
FORCEADD QUANTA_TITLE_BLOCK_C..1
(925 -4650);
FORCEPROP 0 LAST CDS_CON_LAST_MODIFIED Fri Aug 25 14:03:25 2023
J 0
(-960 -4635);
PAINT MONO (-960 -4635);
DISPLAY INVISIBLE (-960 -4635);
FORCEPROP 2 LAST CUSTOM_TXT_CDS <XR_PAGE_TITLE>
J 0
(-6965 600);
DISPLAY 0.638298 (-6965 600);
PAINT PINK (-6965 600);
DISPLAY INVISIBLE (-6965 600);
FORCEPROP 2 LAST CUSTOM_TXT_CDS <Q_REV>
J 0
(741 -4547);
DISPLAY 1.212766 (741 -4547);
FORCEPROP 2 LAST CUSTOM_TXT_CDS <NAME_2>
J 0
(-2250 -4600);
FORCEPROP 2 LAST CUSTOM_TXT_CDS <CON_PAGE_NUM> OF <CON_TOTAL_PAGES>
J 0
(479 -4632);
DISPLAY 0.978723 (479 -4632);
FORCEPROP 2 LAST CUSTOM_TXT_CDS <Q_NUMBER>
J 0
(-478 -4547);
DISPLAY 1.212766 (-478 -4547);
FORCEPROP 2 LAST CUSTOM_TXT_CDS <Q_PROJ>
J 0
(-1457 -4548);
DISPLAY 1.212766 (-1457 -4548);
FORCEPROP 2 LAST CUSTOM_TXT_CDS <NAME_1>
J 0
(-2250 -4475);
FORCEPROP 2 LAST CUSTOM_TXT_CDS <CON_LAST_MODIFIED>
J 0
(-960 -4635);
DISPLAY 0.978723 (-960 -4635);
FORCEPROP 1 LAST Q_TITLE CLK- CK440Q CLK GEN (2/2)
J 0
(-8416 -4624);
DISPLAY 1.957447 (-8416 -4624);
PAINT GREEN (-8416 -4624);
FORCEPROP 1 LAST Q_DEPT 
J 1
(-2838 -4601);
DISPLAY 1.957447 (-2838 -4601);
PAINT GREEN (-2838 -4601);
FORCEPROP 1 LAST COMMENT_BODY TRUE
J 0
(937 -4663);
DISPLAY 0.978723 (937 -4663);
PAINT GREEN (937 -4663);
DISPLAY INVISIBLE (937 -4663);
FORCEPROP 2 LAST PAGE_BORDER TRUE
J 0
(-6965 600);
DISPLAY 0.638298 (-6965 600);
PAINT PINK (-6965 600);
DISPLAY INVISIBLE (-6965 600);
FORCEPROP 1 LAST CDS_LMAN_SYM_OUTLINE -9475,6775,100,-125
J 0
(925 -4650);
DISPLAY 0.468085 (925 -4650);
PAINT GREEN (925 -4650);
DISPLAY INVISIBLE (925 -4650);
FORCEPROP 2 LAST CDS_LIB pure_quanta
J 0
(925 -4650);
PAINT MONO (925 -4650);
DISPLAY INVISIBLE (925 -4650);
FORCEPROP 2 LAST CDS_XR_PAGE_TITLE CR-209 : @S9S_MB_2U_LIB.S9S_MB_2U(SCH_1):PAGE209
J 0
(-6965 600);
DISPLAY 0.638298 (-6965 600);
PAINT PINK (-6965 600);
DISPLAY INVISIBLE (-6965 600);
WIRE 16 -1 (125 1025)(-1575 1025);
FORCEPROP 0 LAST CDS_PHYS_NET_NAME CLK_100M_CK440_PCH_EXTCLK_DP
J 0
(-885 1067);
PAINT MONO (-885 1067);
DISPLAY INVISIBLE (-885 1067);
FORCEPROP 2 LAST SIG_NAME CLK_100M_CK440_PCH_EXTCLK_DP
J 0
(-985 1035);
DISPLAY 0.680851 (-985 1035);
PAINT WHITE (-985 1035);
WIRE 16 -1 (125 850)(-1575 850);
FORCEPROP 0 LAST CDS_PHYS_NET_NAME CLK_100M_CK440_PCH_EXTCLK_DN
J 0
(-885 892);
PAINT MONO (-885 892);
DISPLAY INVISIBLE (-885 892);
FORCEPROP 2 LAST SIG_NAME CLK_100M_CK440_PCH_EXTCLK_DN
J 0
(-985 860);
DISPLAY 0.680851 (-985 860);
PAINT WHITE (-985 860);
WIRE 16 -1 (-1775 1025)(-3050 1025);
FORCEPROP 0 LAST CDS_PHYS_NET_NAME CLK_100M_CK440_PCH_EXTCLK_R_DP
J 0
(-2885 1067);
PAINT MONO (-2885 1067);
DISPLAY INVISIBLE (-2885 1067);
FORCEPROP 2 LAST SIG_NAME CLK_100M_CK440_PCH_EXTCLK_R_DP
J 0
(-2985 1035);
DISPLAY 0.680851 (-2985 1035);
PAINT WHITE (-2985 1035);
WIRE 16 -1 (-1775 850)(-3050 850);
FORCEPROP 0 LAST CDS_PHYS_NET_NAME CLK_100M_CK440_PCH_EXTCLK_R_DN
J 0
(-2885 892);
PAINT MONO (-2885 892);
DISPLAY INVISIBLE (-2885 892);
FORCEPROP 2 LAST SIG_NAME CLK_100M_CK440_PCH_EXTCLK_R_DN
J 0
(-2985 860);
DISPLAY 0.680851 (-2985 860);
PAINT WHITE (-2985 860);
WIRE 16 -1 (-5925 450)(-4225 450);
FORCEPROP 0 LAST CDS_PHYS_NET_NAME CLK_100M_OCP_SFF_1_DN
J 0
(-5235 492);
PAINT MONO (-5235 492);
DISPLAY INVISIBLE (-5235 492);
FORCEPROP 2 LAST SIG_NAME CLK_100M_OCP_SFF_1_DN
J 0
(-5135 460);
DISPLAY 0.680851 (-5135 460);
PAINT WHITE (-5135 460);
WIRE 16 -1 (-5925 850)(-4225 850);
FORCEPROP 0 LAST CDS_PHYS_NET_NAME CLK_100M_OCP_SFF_0_DN
J 0
(-5235 892);
PAINT MONO (-5235 892);
DISPLAY INVISIBLE (-5235 892);
FORCEPROP 2 LAST SIG_NAME CLK_100M_OCP_SFF_0_DN
J 0
(-5135 860);
DISPLAY 0.680851 (-5135 860);
PAINT WHITE (-5135 860);
WIRE 16 -1 (-5925 1000)(-4225 1000);
FORCEPROP 0 LAST CDS_PHYS_NET_NAME CLK_100M_OCP_SFF_0_DP
J 0
(-5235 1042);
PAINT MONO (-5235 1042);
DISPLAY INVISIBLE (-5235 1042);
FORCEPROP 2 LAST SIG_NAME CLK_100M_OCP_SFF_0_DP
J 0
(-5135 1010);
DISPLAY 0.680851 (-5135 1010);
PAINT WHITE (-5135 1010);
WIRE 16 -1 (-5925 600)(-4225 600);
FORCEPROP 0 LAST CDS_PHYS_NET_NAME CLK_100M_OCP_SFF_1_DP
J 0
(-5235 642);
PAINT MONO (-5235 642);
DISPLAY INVISIBLE (-5235 642);
FORCEPROP 2 LAST SIG_NAME CLK_100M_OCP_SFF_1_DP
J 0
(-5135 610);
DISPLAY 0.680851 (-5135 610);
PAINT WHITE (-5135 610);
WIRE 16 -1 (-5925 200)(-4225 200);
FORCEPROP 0 LAST CDS_PHYS_NET_NAME CLK_100M_OCP_SFF_2_DP
J 0
(-5235 242);
PAINT MONO (-5235 242);
DISPLAY INVISIBLE (-5235 242);
FORCEPROP 2 LAST SIG_NAME CLK_100M_OCP_SFF_2_DP
J 0
(-5135 210);
DISPLAY 0.680851 (-5135 210);
PAINT WHITE (-5135 210);
WIRE 16 -1 (-5925 50)(-4225 50);
FORCEPROP 0 LAST CDS_PHYS_NET_NAME CLK_100M_OCP_SFF_2_DN
J 0
(-5235 92);
PAINT MONO (-5235 92);
DISPLAY INVISIBLE (-5235 92);
FORCEPROP 2 LAST SIG_NAME CLK_100M_OCP_SFF_2_DN
J 0
(-5135 60);
DISPLAY 0.680851 (-5135 60);
PAINT WHITE (-5135 60);
WIRE 16 -1 (-6125 600)(-7400 600);
FORCEPROP 0 LAST CDS_PHYS_NET_NAME CLK_100M_OCP_SFF_1_R_DP
J 0
(-7235 642);
PAINT MONO (-7235 642);
DISPLAY INVISIBLE (-7235 642);
FORCEPROP 2 LAST SIG_NAME CLK_100M_OCP_SFF_1_R_DP
J 0
(-7210 610);
DISPLAY 0.680851 (-7210 610);
PAINT WHITE (-7210 610);
WIRE 16 -1 (-6125 50)(-7400 50);
FORCEPROP 0 LAST CDS_PHYS_NET_NAME CLK_100M_OCP_SFF_2_R_DN
J 0
(-7235 92);
PAINT MONO (-7235 92);
DISPLAY INVISIBLE (-7235 92);
FORCEPROP 2 LAST SIG_NAME CLK_100M_OCP_SFF_2_R_DN
J 0
(-7210 60);
DISPLAY 0.680851 (-7210 60);
PAINT WHITE (-7210 60);
WIRE 16 -1 (-6125 1000)(-7400 1000);
FORCEPROP 0 LAST CDS_PHYS_NET_NAME CLK_100M_OCP_SFF_0_R_DP
J 0
(-7235 1042);
PAINT MONO (-7235 1042);
DISPLAY INVISIBLE (-7235 1042);
FORCEPROP 2 LAST SIG_NAME CLK_100M_OCP_SFF_0_R_DP
J 0
(-7210 1010);
DISPLAY 0.680851 (-7210 1010);
PAINT WHITE (-7210 1010);
WIRE 16 -1 (-6125 450)(-7400 450);
FORCEPROP 0 LAST CDS_PHYS_NET_NAME CLK_100M_OCP_SFF_1_R_DN
J 0
(-7235 492);
PAINT MONO (-7235 492);
DISPLAY INVISIBLE (-7235 492);
FORCEPROP 2 LAST SIG_NAME CLK_100M_OCP_SFF_1_R_DN
J 0
(-7210 460);
DISPLAY 0.680851 (-7210 460);
PAINT WHITE (-7210 460);
WIRE 16 -1 (-6125 200)(-7400 200);
FORCEPROP 0 LAST CDS_PHYS_NET_NAME CLK_100M_OCP_SFF_2_R_DP
J 0
(-7235 242);
PAINT MONO (-7235 242);
DISPLAY INVISIBLE (-7235 242);
FORCEPROP 2 LAST SIG_NAME CLK_100M_OCP_SFF_2_R_DP
J 0
(-7210 210);
DISPLAY 0.680851 (-7210 210);
PAINT WHITE (-7210 210);
WIRE 16 -1 (-6125 850)(-7400 850);
FORCEPROP 0 LAST CDS_PHYS_NET_NAME CLK_100M_OCP_SFF_0_R_DN
J 0
(-7235 892);
PAINT MONO (-7235 892);
DISPLAY INVISIBLE (-7235 892);
FORCEPROP 2 LAST SIG_NAME CLK_100M_OCP_SFF_0_R_DN
J 0
(-7210 860);
DISPLAY 0.680851 (-7210 860);
PAINT WHITE (-7210 860);
WIRE 16 2175 (-6300 -425)(-5375 -425);
WIRE 16 2175 (-5375 1150)(-5375 -425);
WIRE 16 2175 (-6300 1150)(-6300 -425);
WIRE 16 2175 (-6300 1150)(-5375 1150);
WIRE 16 -1 (-4025 -1075)(-4275 -1075);
WIRE 16 -1 (-3125 -1075)(-4025 -1075);
FORCEPROP 2 LAST SIG_NAME CLK_25M_NSSC_CPU0_DP
J 0
(-3935 -1065);
DISPLAY 0.680851 (-3935 -1065);
PAINT WHITE (-3935 -1065);
WIRE 16 -1 (-4025 -1075)(-4025 -1250);
WIRE 16 -1 (-6000 -1250)(-4025 -1250);
WIRE 16 -1 (-4025 -1425)(-4275 -1425);
WIRE 16 -1 (-3125 -1425)(-4025 -1425);
FORCEPROP 2 LAST SIG_NAME CLK_25M_NSSC_CPU0_DN
J 0
(-3935 -1415);
DISPLAY 0.680851 (-3935 -1415);
PAINT WHITE (-3935 -1415);
WIRE 16 -1 (-4025 -1425)(-4025 -1600);
WIRE 16 -1 (-6000 -1600)(-4025 -1600);
WIRE 16 -1 (-5925 -350)(-4225 -350);
FORCEPROP 0 LAST CDS_PHYS_NET_NAME CLK_100M_OCP_SFF_3_DN
J 0
(-5235 -308);
PAINT MONO (-5235 -308);
DISPLAY INVISIBLE (-5235 -308);
FORCEPROP 2 LAST SIG_NAME CLK_100M_OCP_SFF_3_DN
J 0
(-5135 -340);
DISPLAY 0.680851 (-5135 -340);
PAINT WHITE (-5135 -340);
WIRE 16 -1 (-5925 -200)(-4225 -200);
FORCEPROP 0 LAST CDS_PHYS_NET_NAME CLK_100M_OCP_SFF_3_DP
J 0
(-5235 -158);
PAINT MONO (-5235 -158);
DISPLAY INVISIBLE (-5235 -158);
FORCEPROP 2 LAST SIG_NAME CLK_100M_OCP_SFF_3_DP
J 0
(-5135 -190);
DISPLAY 0.680851 (-5135 -190);
PAINT WHITE (-5135 -190);
WIRE 16 -1 (-4025 -2375)(-4275 -2375);
WIRE 16 -1 (-3125 -2375)(-4025 -2375);
FORCEPROP 2 LAST SIG_NAME CLK_25M_NSSC_CPU1_DP
J 0
(-3935 -2365);
DISPLAY 0.680851 (-3935 -2365);
PAINT WHITE (-3935 -2365);
WIRE 16 -1 (-4025 -2375)(-4025 -2550);
WIRE 16 -1 (-6000 -2550)(-4025 -2550);
WIRE 16 -1 (-4025 -2725)(-4275 -2725);
WIRE 16 -1 (-3125 -2725)(-4025 -2725);
FORCEPROP 2 LAST SIG_NAME CLK_25M_NSSC_CPU1_DN
J 0
(-3935 -2715);
DISPLAY 0.680851 (-3935 -2715);
PAINT WHITE (-3935 -2715);
WIRE 16 -1 (-4025 -2725)(-4025 -2900);
WIRE 16 -1 (-6000 -2900)(-4025 -2900);
WIRE 16 -1 (-6025 -3825)(-4600 -3825);
FORCEPROP 2 LAST SIG_NAME CLK_25M_PCH_REF_NS_DN
J 0
(-5510 -3815);
DISPLAY 0.680851 (-5510 -3815);
PAINT WHITE (-5510 -3815);
WIRE 16 -1 (-6000 -2725)(-4475 -2725);
FORCEPROP 2 LAST SIG_NAME CLK_25M_CK440_CPU1_R_DN
J 0
(-5635 -2715);
DISPLAY 0.680851 (-5635 -2715);
PAINT WHITE (-5635 -2715);
WIRE 16 -1 (-6025 -3650)(-4600 -3650);
FORCEPROP 2 LAST SIG_NAME CLK_25M_PCH_REF_NS_DP
J 0
(-5510 -3640);
DISPLAY 0.680851 (-5510 -3640);
PAINT WHITE (-5510 -3640);
WIRE 16 -1 (-6000 -1075)(-4475 -1075);
FORCEPROP 2 LAST SIG_NAME CLK_25M_CK440_CPU0_R_DP
J 0
(-5635 -1065);
DISPLAY 0.680851 (-5635 -1065);
PAINT WHITE (-5635 -1065);
WIRE 16 -1 (-6000 -2375)(-4475 -2375);
FORCEPROP 2 LAST SIG_NAME CLK_25M_CK440_CPU1_R_DP
J 0
(-5635 -2365);
DISPLAY 0.680851 (-5635 -2365);
PAINT WHITE (-5635 -2365);
WIRE 16 -1 (-6000 -1425)(-4475 -1425);
FORCEPROP 2 LAST SIG_NAME CLK_25M_CK440_CPU0_R_DN
J 0
(-5635 -1415);
DISPLAY 0.680851 (-5635 -1415);
PAINT WHITE (-5635 -1415);
WIRE 16 -1 (-6125 -200)(-7400 -200);
FORCEPROP 0 LAST CDS_PHYS_NET_NAME CLK_100M_OCP_SFF_3_R_DP
J 0
(-7235 -158);
PAINT MONO (-7235 -158);
DISPLAY INVISIBLE (-7235 -158);
FORCEPROP 2 LAST SIG_NAME CLK_100M_OCP_SFF_3_R_DP
J 0
(-7210 -190);
DISPLAY 0.680851 (-7210 -190);
PAINT WHITE (-7210 -190);
WIRE 16 -1 (-7425 -1250)(-6200 -1250);
FORCEPROP 2 LAST SIG_NAME CLK_25M_PCH_CPU0_DP
J 0
(-7310 -1240);
DISPLAY 0.680851 (-7310 -1240);
PAINT WHITE (-7310 -1240);
WIRE 16 -1 (-7425 -1425)(-6200 -1425);
FORCEPROP 2 LAST SIG_NAME CLK_25M_CK440_CPU0_DN
J 0
(-7310 -1415);
DISPLAY 0.680851 (-7310 -1415);
PAINT WHITE (-7310 -1415);
WIRE 16 -1 (-7425 -1600)(-6200 -1600);
FORCEPROP 2 LAST SIG_NAME CLK_25M_PCH_CPU0_DN
J 0
(-7310 -1590);
DISPLAY 0.680851 (-7310 -1590);
PAINT WHITE (-7310 -1590);
WIRE 16 -1 (-7425 -1075)(-6200 -1075);
FORCEPROP 2 LAST SIG_NAME CLK_25M_CK440_CPU0_DP
J 0
(-7310 -1065);
DISPLAY 0.680851 (-7310 -1065);
PAINT WHITE (-7310 -1065);
WIRE 16 -1 (-6125 -350)(-7400 -350);
FORCEPROP 0 LAST CDS_PHYS_NET_NAME CLK_100M_OCP_SFF_3_R_DN
J 0
(-7235 -308);
PAINT MONO (-7235 -308);
DISPLAY INVISIBLE (-7235 -308);
FORCEPROP 2 LAST SIG_NAME CLK_100M_OCP_SFF_3_R_DN
J 0
(-7210 -340);
DISPLAY 0.680851 (-7210 -340);
PAINT WHITE (-7210 -340);
WIRE 16 -1 (-7450 -3825)(-6225 -3825);
FORCEPROP 2 LAST SIG_NAME CLK_25M_CK440_ISCLK_REF_DN
J 0
(-7335 -3815);
DISPLAY 0.680851 (-7335 -3815);
PAINT WHITE (-7335 -3815);
WIRE 16 -1 (-7425 -2375)(-6200 -2375);
FORCEPROP 2 LAST SIG_NAME CLK_25M_CK440_CPU1_DP
J 0
(-7310 -2365);
DISPLAY 0.680851 (-7310 -2365);
PAINT WHITE (-7310 -2365);
WIRE 16 -1 (-7425 -2550)(-6200 -2550);
FORCEPROP 2 LAST SIG_NAME CLK_25M_PCH_CPU1_DP
J 0
(-7310 -2540);
DISPLAY 0.680851 (-7310 -2540);
PAINT WHITE (-7310 -2540);
WIRE 16 -1 (-7425 -2725)(-6200 -2725);
FORCEPROP 2 LAST SIG_NAME CLK_25M_CK440_CPU1_DN
J 0
(-7310 -2715);
DISPLAY 0.680851 (-7310 -2715);
PAINT WHITE (-7310 -2715);
WIRE 16 -1 (-7425 -2900)(-6200 -2900);
FORCEPROP 2 LAST SIG_NAME CLK_25M_PCH_CPU1_DN
J 0
(-7310 -2890);
DISPLAY 0.680851 (-7310 -2890);
PAINT WHITE (-7310 -2890);
WIRE 16 -1 (-7450 -3650)(-6225 -3650);
FORCEPROP 2 LAST SIG_NAME CLK_25M_CK440_ISCLK_REF_DP
J 0
(-7335 -3640);
DISPLAY 0.680851 (-7335 -3640);
PAINT WHITE (-7335 -3640);
DOT 1 (-4025 -2725);
DOT 1 (-4025 -2375);
DOT 1 (-4025 -1425);
DOT 1 (-4025 -1075);
FORCENOTE
20221215 CHANGE R563,R564,R565,R566,R1273,R1274,R1275,R1276 TO 22 OHM
(-7300 -500) 0;
DISPLAY LEFT (-7300 -500);
DISPLAY 1.063830 (-7300 -500);
PAINT WHITE (-7300 -500);
FORCENOTE
20210602 MODIFY FOR GT
(-7375 1600) 0;
DISPLAY LEFT (-7375 1600);
DISPLAY 2.510638 (-7375 1600);
PAINT PINK (-7375 1600);
FORCENOTE
SFF_OCP
(-4675 1175) 0;
DISPLAY LEFT (-4675 1175);
DISPLAY 2.000000 (-4675 1175);
PAINT SKYBLUE (-4675 1175);
FORCENOTE
PCH
(50 1175) 0;
DISPLAY LEFT (50 1175);
DISPLAY 2.000000 (50 1175);
PAINT SKYBLUE (50 1175);
QUIT
